G04 ================== begin FILE IDENTIFICATION RECORD ==================*
G04 Layout Name:  D:/<user>/Wistron_project/16315-1/gbr/16315-1.brd*
G04 Film Name:    SE_REF_L10*
G04 File Format:  Gerber RS274X*
G04 File Origin:  Cadence Allegro 16.5-S056*
G04 Origin Date:  Fri Jun 09 15:33:10 2017*
G04 *
G04 Layer:  BOARD GEOMETRY/SE_REF_L10_TBL*
G04 Layer:  BOARD GEOMETRY/SE_REF_L10_L10*
G04 Layer:  BOARD GEOMETRY/PANEL_OUTLINE*
G04 *
G04 Offset:    (0.00 0.00)*
G04 Mirror:    No*
G04 Mode:      Positive*
G04 Rotation:  0*
G04 FullContactRelief:  No*
G04 UndefLineWidth:     6.00*
G04 ================== end FILE IDENTIFICATION RECORD ====================*
%FSLAX35Y35*MOIN*%
%IR0*IPPOS*OFA0.00000B0.00000*MIA0B0*SFA1.00000B1.00000*%
%ADD10C,.02*%
%ADD11C,.006*%
%ADD12C,.00525*%
G75*
%LPD*%
G75*
G54D10*
G01X1985143Y1554618D02*
X2737643D01*
G01X1985143Y1623918D02*
Y1554618D01*
G01Y1589268D02*
X2737643D01*
G01X1985143Y1623918D02*
X2737643D01*
G01X2160143D02*
Y1554618D01*
G01X2422643Y1623918D02*
Y1554618D01*
G01X2527643Y1623918D02*
Y1554618D01*
G01X2737643Y1623918D02*
Y1554618D01*
G54D11*
G01X6250Y-185556D02*
Y-203056D01*
G01X1228Y-185556D02*
X11272D01*
G01X20038Y-203056D02*
Y-185556D01*
G01Y-194014D02*
X21130Y-192556D01*
X22222Y-191681D01*
X23968Y-191390D01*
X25278Y-191681D01*
X26807Y-192848D01*
X27462Y-194598D01*
Y-203056D01*
G01X41250Y-191390D02*
Y-203056D01*
G01Y-186723D02*
X40813Y-186431D01*
Y-185848D01*
X41250Y-185556D01*
X41687Y-185848D01*
Y-186431D01*
X41250Y-186723D01*
G01X55475Y-201015D02*
X56567Y-202181D01*
X58095Y-203056D01*
X59405D01*
X60715Y-202473D01*
X61588Y-201598D01*
X62025Y-200432D01*
X61807Y-198681D01*
X60933Y-197806D01*
X57003Y-196056D01*
X56130Y-194014D01*
X56567Y-192556D01*
X57440Y-191681D01*
X58750Y-191390D01*
X60060Y-191681D01*
X61370Y-192556D01*
G01X90693Y-207431D02*
X92222Y-208598D01*
X93968Y-208889D01*
X95496Y-208598D01*
X96807Y-207140D01*
X97680Y-205098D01*
Y-191390D01*
G01Y-193723D02*
X96807Y-192556D01*
X95496Y-191681D01*
X93968Y-191390D01*
X92222Y-191973D01*
X91130Y-193139D01*
X90256Y-195181D01*
X89820Y-197223D01*
X90038Y-198973D01*
X90912Y-201015D01*
X92222Y-202473D01*
X93968Y-203056D01*
X95278Y-202764D01*
X96807Y-201598D01*
X97680Y-200432D01*
G01X107975Y-195181D02*
X114962D01*
X114307Y-193139D01*
X113215Y-191973D01*
X111687Y-191390D01*
X110158Y-191681D01*
X108848Y-192556D01*
X107975Y-194598D01*
X107538Y-196348D01*
Y-198098D01*
X107975Y-199848D01*
X109067Y-201598D01*
X110377Y-202764D01*
X111905Y-203056D01*
X113433Y-202473D01*
X114962Y-200723D01*
G01X125693Y-203056D02*
Y-191390D01*
G01Y-193723D02*
X126785Y-192556D01*
X127877Y-191681D01*
X129405Y-191390D01*
X130496Y-191681D01*
X131807Y-192556D01*
G01X142320Y-203056D02*
Y-185556D01*
G01Y-194306D02*
X143412Y-192556D01*
X144722Y-191681D01*
X146032Y-191390D01*
X147996Y-191973D01*
X149307Y-193139D01*
X150180Y-195181D01*
Y-197514D01*
X149743Y-199848D01*
X148870Y-201598D01*
X147342Y-202764D01*
X146032Y-203056D01*
X144722Y-202764D01*
X143412Y-201890D01*
X142320Y-200432D01*
G01X160475Y-195181D02*
X167462D01*
X166807Y-193139D01*
X165715Y-191973D01*
X164187Y-191390D01*
X162658Y-191681D01*
X161348Y-192556D01*
X160475Y-194598D01*
X160038Y-196348D01*
Y-198098D01*
X160475Y-199848D01*
X161567Y-201598D01*
X162877Y-202764D01*
X164405Y-203056D01*
X165933Y-202473D01*
X167462Y-200723D01*
G01X178193Y-203056D02*
Y-191390D01*
G01Y-193723D02*
X179285Y-192556D01*
X180377Y-191681D01*
X181905Y-191390D01*
X182996Y-191681D01*
X184307Y-192556D01*
G01X216250Y-191390D02*
Y-203056D01*
G01Y-186723D02*
X215813Y-186431D01*
Y-185848D01*
X216250Y-185556D01*
X216687Y-185848D01*
Y-186431D01*
X216250Y-186723D01*
G01X230475Y-201015D02*
X231567Y-202181D01*
X233095Y-203056D01*
X234405D01*
X235715Y-202473D01*
X236588Y-201598D01*
X237025Y-200432D01*
X236807Y-198681D01*
X235933Y-197806D01*
X232003Y-196056D01*
X231130Y-194014D01*
X231567Y-192556D01*
X232440Y-191681D01*
X233750Y-191390D01*
X235060Y-191681D01*
X236370Y-192556D01*
G01X265256Y-207431D02*
X266785Y-208598D01*
X268095Y-208889D01*
X269842Y-208306D01*
X271152Y-206848D01*
X271807Y-204222D01*
Y-191390D01*
G01Y-186723D02*
X271370Y-186431D01*
Y-185848D01*
X271807Y-185556D01*
X272243Y-185848D01*
Y-186431D01*
X271807Y-186723D01*
G01X282538Y-191390D02*
Y-199556D01*
X283412Y-201598D01*
X284722Y-202764D01*
X286250Y-203056D01*
X287778Y-202764D01*
X289088Y-201598D01*
X289962Y-199556D01*
G01Y-203056D02*
Y-191390D01*
G01X300475Y-201015D02*
X301567Y-202181D01*
X303095Y-203056D01*
X304405D01*
X305715Y-202473D01*
X306588Y-201598D01*
X307025Y-200432D01*
X306807Y-198681D01*
X305933Y-197806D01*
X302003Y-196056D01*
X301130Y-194014D01*
X301567Y-192556D01*
X302440Y-191681D01*
X303750Y-191390D01*
X305060Y-191681D01*
X306370Y-192556D01*
G01X321250Y-185556D02*
Y-203056D01*
G01X318193Y-191390D02*
X324307D01*
G01X354940Y-203056D02*
Y-188181D01*
X355377Y-186723D01*
X356250Y-185848D01*
X357560Y-185556D01*
X358870Y-186139D01*
X359525Y-187598D01*
G01X356905Y-192556D02*
X352538D01*
G01X373750Y-203056D02*
X372440Y-202764D01*
X371130Y-201598D01*
X370256Y-199556D01*
X369820Y-197223D01*
X370256Y-194889D01*
X371130Y-192848D01*
X372440Y-191681D01*
X373750Y-191390D01*
X375060Y-191681D01*
X376370Y-192848D01*
X377243Y-194889D01*
X377462Y-197223D01*
X377243Y-199556D01*
X376370Y-201598D01*
X375060Y-202764D01*
X373750Y-203056D01*
G01X388193D02*
Y-191390D01*
G01Y-193723D02*
X389285Y-192556D01*
X390377Y-191681D01*
X391905Y-191390D01*
X392996Y-191681D01*
X394307Y-192556D01*
G01X421665Y-208306D02*
X422975Y-208889D01*
X424722Y-208306D01*
X425813Y-207140D01*
X426687Y-205681D01*
X427996Y-201015D01*
X430835Y-191390D01*
G01X423848D02*
X427996Y-201015D01*
G01X443750Y-203056D02*
X442440Y-202764D01*
X441130Y-201598D01*
X440256Y-199556D01*
X439820Y-197223D01*
X440256Y-194889D01*
X441130Y-192848D01*
X442440Y-191681D01*
X443750Y-191390D01*
X445060Y-191681D01*
X446370Y-192848D01*
X447243Y-194889D01*
X447462Y-197223D01*
X447243Y-199556D01*
X446370Y-201598D01*
X445060Y-202764D01*
X443750Y-203056D01*
G01X457538Y-191390D02*
Y-199556D01*
X458412Y-201598D01*
X459722Y-202764D01*
X461250Y-203056D01*
X462778Y-202764D01*
X464088Y-201598D01*
X464962Y-199556D01*
G01Y-203056D02*
Y-191390D01*
G01X475693Y-203056D02*
Y-191390D01*
G01Y-193723D02*
X476785Y-192556D01*
X477877Y-191681D01*
X479405Y-191390D01*
X480496Y-191681D01*
X481807Y-192556D01*
G01X510693Y-203056D02*
Y-191390D01*
G01Y-193723D02*
X511785Y-192556D01*
X512877Y-191681D01*
X514405Y-191390D01*
X515496Y-191681D01*
X516807Y-192556D01*
G01X527975Y-195181D02*
X534962D01*
X534307Y-193139D01*
X533215Y-191973D01*
X531687Y-191390D01*
X530158Y-191681D01*
X528848Y-192556D01*
X527975Y-194598D01*
X527538Y-196348D01*
Y-198098D01*
X527975Y-199848D01*
X529067Y-201598D01*
X530377Y-202764D01*
X531905Y-203056D01*
X533433Y-202473D01*
X534962Y-200723D01*
G01X547440Y-203056D02*
Y-188181D01*
X547877Y-186723D01*
X548750Y-185848D01*
X550060Y-185556D01*
X551370Y-186139D01*
X552025Y-187598D01*
G01X549405Y-192556D02*
X545038D01*
G01X562975Y-195181D02*
X569962D01*
X569307Y-193139D01*
X568215Y-191973D01*
X566687Y-191390D01*
X565158Y-191681D01*
X563848Y-192556D01*
X562975Y-194598D01*
X562538Y-196348D01*
Y-198098D01*
X562975Y-199848D01*
X564067Y-201598D01*
X565377Y-202764D01*
X566905Y-203056D01*
X568433Y-202473D01*
X569962Y-200723D01*
G01X580693Y-203056D02*
Y-191390D01*
G01Y-193723D02*
X581785Y-192556D01*
X582877Y-191681D01*
X584405Y-191390D01*
X585496Y-191681D01*
X586807Y-192556D01*
G01X597975Y-195181D02*
X604962D01*
X604307Y-193139D01*
X603215Y-191973D01*
X601687Y-191390D01*
X600158Y-191681D01*
X598848Y-192556D01*
X597975Y-194598D01*
X597538Y-196348D01*
Y-198098D01*
X597975Y-199848D01*
X599067Y-201598D01*
X600377Y-202764D01*
X601905Y-203056D01*
X603433Y-202473D01*
X604962Y-200723D01*
G01X615038Y-203056D02*
Y-191390D01*
G01Y-194306D02*
X615912Y-192848D01*
X617222Y-191681D01*
X618968Y-191390D01*
X620496Y-191681D01*
X621807Y-192848D01*
X622462Y-194889D01*
Y-203056D01*
G01X639743Y-192848D02*
X638215Y-191681D01*
X636905Y-191390D01*
X635158Y-191973D01*
X633848Y-193139D01*
X632975Y-195181D01*
X632756Y-197223D01*
X632975Y-199265D01*
X633848Y-201015D01*
X635158Y-202473D01*
X636905Y-203056D01*
X638433Y-202473D01*
X639743Y-201306D01*
G01X650475Y-195181D02*
X657462D01*
X656807Y-193139D01*
X655715Y-191973D01*
X654187Y-191390D01*
X652658Y-191681D01*
X651348Y-192556D01*
X650475Y-194598D01*
X650038Y-196348D01*
Y-198098D01*
X650475Y-199848D01*
X651567Y-201598D01*
X652877Y-202764D01*
X654405Y-203056D01*
X655933Y-202473D01*
X657462Y-200723D01*
G01X688750Y-185556D02*
Y-203056D01*
G01X685693Y-191390D02*
X691807D01*
G01X706250Y-203056D02*
X704940Y-202764D01*
X703630Y-201598D01*
X702756Y-199556D01*
X702320Y-197223D01*
X702756Y-194889D01*
X703630Y-192848D01*
X704940Y-191681D01*
X706250Y-191390D01*
X707560Y-191681D01*
X708870Y-192848D01*
X709743Y-194889D01*
X709962Y-197223D01*
X709743Y-199556D01*
X708870Y-201598D01*
X707560Y-202764D01*
X706250Y-203056D01*
G01X739940D02*
Y-188181D01*
X740377Y-186723D01*
X741250Y-185848D01*
X742560Y-185556D01*
X743870Y-186139D01*
X744525Y-187598D01*
G01X741905Y-192556D02*
X737538D01*
G01X758750Y-191390D02*
Y-203056D01*
G01Y-186723D02*
X758313Y-186431D01*
Y-185848D01*
X758750Y-185556D01*
X759187Y-185848D01*
Y-186431D01*
X758750Y-186723D01*
G01X772538Y-203056D02*
Y-191390D01*
G01Y-194306D02*
X773412Y-192848D01*
X774722Y-191681D01*
X776468Y-191390D01*
X777996Y-191681D01*
X779307Y-192848D01*
X779962Y-194889D01*
Y-203056D01*
G01X797680Y-185556D02*
Y-203056D01*
G01Y-200432D02*
X796807Y-201890D01*
X795496Y-202764D01*
X793968Y-203056D01*
X792222Y-202473D01*
X790912Y-201015D01*
X790038Y-199265D01*
X789820Y-197223D01*
X790038Y-195181D01*
X790912Y-193431D01*
X792222Y-191973D01*
X793968Y-191390D01*
X795496Y-191681D01*
X796588Y-192265D01*
X797680Y-193431D01*
G01X828750Y-185556D02*
Y-203056D01*
G01X825693Y-191390D02*
X831807D01*
G01X842538Y-203056D02*
Y-185556D01*
G01Y-194014D02*
X843630Y-192556D01*
X844722Y-191681D01*
X846468Y-191390D01*
X847778Y-191681D01*
X849307Y-192848D01*
X849962Y-194598D01*
Y-203056D01*
G01X860475Y-195181D02*
X867462D01*
X866807Y-193139D01*
X865715Y-191973D01*
X864187Y-191390D01*
X862658Y-191681D01*
X861348Y-192556D01*
X860475Y-194598D01*
X860038Y-196348D01*
Y-198098D01*
X860475Y-199848D01*
X861567Y-201598D01*
X862877Y-202764D01*
X864405Y-203056D01*
X865933Y-202473D01*
X867462Y-200723D01*
G01X894165D02*
X895912Y-202181D01*
X897877Y-203056D01*
X899623D01*
X901370Y-202181D01*
X902680Y-200723D01*
X903335Y-198681D01*
X902898Y-196640D01*
X901807Y-194889D01*
X899842Y-193723D01*
X897222Y-193139D01*
X895693Y-191973D01*
X895038Y-189931D01*
X895475Y-187889D01*
X896567Y-186431D01*
X898095Y-185556D01*
X899623D01*
X901152Y-186139D01*
X902462Y-187598D01*
G01X920617Y-203056D02*
X911883D01*
Y-185556D01*
X920617D01*
G01X917123Y-194014D02*
X911883D01*
G01X951250Y-191390D02*
Y-203056D01*
G01Y-186723D02*
X950813Y-186431D01*
Y-185848D01*
X951250Y-185556D01*
X951687Y-185848D01*
Y-186431D01*
X951250Y-186723D01*
G01X962200Y-203056D02*
Y-191390D01*
G01Y-194598D02*
X962855Y-193139D01*
X963947Y-191973D01*
X965475Y-191390D01*
X967003Y-191973D01*
X968095Y-193139D01*
X968750Y-194598D01*
Y-203056D01*
G01Y-194598D02*
X969405Y-193139D01*
X970496Y-191973D01*
X972025Y-191390D01*
X973553Y-191973D01*
X974645Y-193139D01*
X975300Y-194889D01*
Y-203056D01*
G01X982320Y-208889D02*
Y-191390D01*
G01Y-194014D02*
X983412Y-192556D01*
X984503Y-191681D01*
X986250Y-191390D01*
X987778Y-191681D01*
X989307Y-193139D01*
X989962Y-195181D01*
X990180Y-197223D01*
X989962Y-199265D01*
X989307Y-201306D01*
X987996Y-202473D01*
X986250Y-203056D01*
X984722Y-202764D01*
X983193Y-201890D01*
X982320Y-200723D01*
G01X1000475Y-195181D02*
X1007462D01*
X1006807Y-193139D01*
X1005715Y-191973D01*
X1004187Y-191390D01*
X1002658Y-191681D01*
X1001348Y-192556D01*
X1000475Y-194598D01*
X1000038Y-196348D01*
Y-198098D01*
X1000475Y-199848D01*
X1001567Y-201598D01*
X1002877Y-202764D01*
X1004405Y-203056D01*
X1005933Y-202473D01*
X1007462Y-200723D01*
G01X1025180Y-185556D02*
Y-203056D01*
G01Y-200432D02*
X1024307Y-201890D01*
X1022996Y-202764D01*
X1021468Y-203056D01*
X1019722Y-202473D01*
X1018412Y-201015D01*
X1017538Y-199265D01*
X1017320Y-197223D01*
X1017538Y-195181D01*
X1018412Y-193431D01*
X1019722Y-191973D01*
X1021468Y-191390D01*
X1022996Y-191681D01*
X1024088Y-192265D01*
X1025180Y-193431D01*
G01X1042680Y-203056D02*
Y-191390D01*
G01Y-193431D02*
X1041807Y-192265D01*
X1040496Y-191681D01*
X1038968Y-191390D01*
X1037440Y-191973D01*
X1036130Y-193139D01*
X1035256Y-194889D01*
X1034820Y-197223D01*
X1035256Y-199556D01*
X1036130Y-201306D01*
X1037440Y-202473D01*
X1038968Y-203056D01*
X1040496Y-202764D01*
X1041807Y-201890D01*
X1042680Y-200723D01*
G01X1052538Y-203056D02*
Y-191390D01*
G01Y-194306D02*
X1053412Y-192848D01*
X1054722Y-191681D01*
X1056468Y-191390D01*
X1057996Y-191681D01*
X1059307Y-192848D01*
X1059962Y-194889D01*
Y-203056D01*
G01X1077243Y-192848D02*
X1075715Y-191681D01*
X1074405Y-191390D01*
X1072658Y-191973D01*
X1071348Y-193139D01*
X1070475Y-195181D01*
X1070256Y-197223D01*
X1070475Y-199265D01*
X1071348Y-201015D01*
X1072658Y-202473D01*
X1074405Y-203056D01*
X1075933Y-202473D01*
X1077243Y-201306D01*
G01X1087975Y-195181D02*
X1094962D01*
X1094307Y-193139D01*
X1093215Y-191973D01*
X1091687Y-191390D01*
X1090158Y-191681D01*
X1088848Y-192556D01*
X1087975Y-194598D01*
X1087538Y-196348D01*
Y-198098D01*
X1087975Y-199848D01*
X1089067Y-201598D01*
X1090377Y-202764D01*
X1091905Y-203056D01*
X1093433Y-202473D01*
X1094962Y-200723D01*
G01X1126250Y-185556D02*
Y-203056D01*
G01X1123193Y-191390D02*
X1129307D01*
G01X1140693Y-203056D02*
Y-191390D01*
G01Y-193723D02*
X1141785Y-192556D01*
X1142877Y-191681D01*
X1144405Y-191390D01*
X1145496Y-191681D01*
X1146807Y-192556D01*
G01X1165180Y-203056D02*
Y-191390D01*
G01Y-193431D02*
X1164307Y-192265D01*
X1162996Y-191681D01*
X1161468Y-191390D01*
X1159940Y-191973D01*
X1158630Y-193139D01*
X1157756Y-194889D01*
X1157320Y-197223D01*
X1157756Y-199556D01*
X1158630Y-201306D01*
X1159940Y-202473D01*
X1161468Y-203056D01*
X1162996Y-202764D01*
X1164307Y-201890D01*
X1165180Y-200723D01*
G01X1182243Y-192848D02*
X1180715Y-191681D01*
X1179405Y-191390D01*
X1177658Y-191973D01*
X1176348Y-193139D01*
X1175475Y-195181D01*
X1175256Y-197223D01*
X1175475Y-199265D01*
X1176348Y-201015D01*
X1177658Y-202473D01*
X1179405Y-203056D01*
X1180933Y-202473D01*
X1182243Y-201306D01*
G01X1192975Y-195181D02*
X1199962D01*
X1199307Y-193139D01*
X1198215Y-191973D01*
X1196687Y-191390D01*
X1195158Y-191681D01*
X1193848Y-192556D01*
X1192975Y-194598D01*
X1192538Y-196348D01*
Y-198098D01*
X1192975Y-199848D01*
X1194067Y-201598D01*
X1195377Y-202764D01*
X1196905Y-203056D01*
X1198433Y-202473D01*
X1199962Y-200723D01*
G01X1210475Y-201015D02*
X1211567Y-202181D01*
X1213095Y-203056D01*
X1214405D01*
X1215715Y-202473D01*
X1216588Y-201598D01*
X1217025Y-200432D01*
X1216807Y-198681D01*
X1215933Y-197806D01*
X1212003Y-196056D01*
X1211130Y-194014D01*
X1211567Y-192556D01*
X1212440Y-191681D01*
X1213750Y-191390D01*
X1215060Y-191681D01*
X1216370Y-192556D01*
G01X1248750Y-191390D02*
Y-203056D01*
G01Y-186723D02*
X1248313Y-186431D01*
Y-185848D01*
X1248750Y-185556D01*
X1249187Y-185848D01*
Y-186431D01*
X1248750Y-186723D01*
G01X1262538Y-203056D02*
Y-191390D01*
G01Y-194306D02*
X1263412Y-192848D01*
X1264722Y-191681D01*
X1266468Y-191390D01*
X1267996Y-191681D01*
X1269307Y-192848D01*
X1269962Y-194889D01*
Y-203056D01*
G01X1301250D02*
Y-185556D01*
G01X1322680Y-203056D02*
Y-191390D01*
G01Y-193431D02*
X1321807Y-192265D01*
X1320496Y-191681D01*
X1318968Y-191390D01*
X1317440Y-191973D01*
X1316130Y-193139D01*
X1315256Y-194889D01*
X1314820Y-197223D01*
X1315256Y-199556D01*
X1316130Y-201306D01*
X1317440Y-202473D01*
X1318968Y-203056D01*
X1320496Y-202764D01*
X1321807Y-201890D01*
X1322680Y-200723D01*
G01X1331665Y-208306D02*
X1332975Y-208889D01*
X1334722Y-208306D01*
X1335813Y-207140D01*
X1336687Y-205681D01*
X1337996Y-201015D01*
X1340835Y-191390D01*
G01X1333848D02*
X1337996Y-201015D01*
G01X1350475Y-195181D02*
X1357462D01*
X1356807Y-193139D01*
X1355715Y-191973D01*
X1354187Y-191390D01*
X1352658Y-191681D01*
X1351348Y-192556D01*
X1350475Y-194598D01*
X1350038Y-196348D01*
Y-198098D01*
X1350475Y-199848D01*
X1351567Y-201598D01*
X1352877Y-202764D01*
X1354405Y-203056D01*
X1355933Y-202473D01*
X1357462Y-200723D01*
G01X1368193Y-203056D02*
Y-191390D01*
G01Y-193723D02*
X1369285Y-192556D01*
X1370377Y-191681D01*
X1371905Y-191390D01*
X1372996Y-191681D01*
X1374307Y-192556D01*
G01X1401883Y-185556D02*
Y-203056D01*
X1410617D01*
G01X1423750D02*
Y-185556D01*
X1421130Y-189056D01*
G01Y-203056D02*
X1426370D01*
G01X1441250Y-185556D02*
X1439503Y-186139D01*
X1438193Y-187598D01*
X1437320Y-189347D01*
X1436665Y-191681D01*
X1436447Y-194306D01*
X1436665Y-196931D01*
X1437320Y-199265D01*
X1438193Y-201015D01*
X1439503Y-202473D01*
X1441250Y-203056D01*
X1442996Y-202473D01*
X1444307Y-201015D01*
X1445180Y-199265D01*
X1445835Y-196931D01*
X1446053Y-194306D01*
X1445835Y-191681D01*
X1445180Y-189347D01*
X1444307Y-187598D01*
X1442996Y-186139D01*
X1441250Y-185556D01*
G01X1458750Y-203639D02*
X1458313Y-203348D01*
Y-202764D01*
X1458750Y-202473D01*
X1459187Y-202764D01*
Y-203348D01*
X1458750Y-203639D01*
G01X2008773Y1616518D02*
X2014013D01*
G01X2011393D02*
Y1599018D01*
G01X2008773D02*
X2014013D01*
G01X2023216D02*
Y1616518D01*
X2028893Y1601935D01*
X2034570Y1616518D01*
Y1599018D01*
G01X2042026D02*
Y1616518D01*
X2047266D01*
X2049013Y1615643D01*
X2050323Y1613601D01*
X2050760Y1611268D01*
X2050323Y1608935D01*
X2049231Y1607185D01*
X2047266Y1606309D01*
X2042026D01*
G01X2062801Y1593185D02*
X2060618Y1596101D01*
X2059526Y1599018D01*
Y1610684D01*
X2060618Y1613601D01*
X2062801Y1616518D01*
G01X2081393Y1599018D02*
X2079646Y1599310D01*
X2078118Y1600476D01*
X2076808Y1602226D01*
X2075934Y1604268D01*
X2075498Y1606601D01*
Y1608935D01*
X2075934Y1611268D01*
X2076808Y1613310D01*
X2078118Y1615059D01*
X2079646Y1616226D01*
X2081393Y1616518D01*
X2083139Y1616226D01*
X2084668Y1615059D01*
X2085978Y1613310D01*
X2086852Y1611268D01*
X2087288Y1608935D01*
Y1606601D01*
X2086852Y1604268D01*
X2085978Y1602226D01*
X2084668Y1600476D01*
X2083139Y1599310D01*
X2081393Y1599018D01*
G01X2095181D02*
Y1616518D01*
G01Y1608060D02*
X2096273Y1609518D01*
X2097365Y1610393D01*
X2099111Y1610684D01*
X2100421Y1610393D01*
X2101950Y1609226D01*
X2102605Y1607476D01*
Y1599018D01*
G01X2109843D02*
Y1610684D01*
G01Y1607476D02*
X2110498Y1608935D01*
X2111590Y1610101D01*
X2113118Y1610684D01*
X2114646Y1610101D01*
X2115738Y1608935D01*
X2116393Y1607476D01*
Y1599018D01*
G01Y1607476D02*
X2117048Y1608935D01*
X2118139Y1610101D01*
X2119668Y1610684D01*
X2121196Y1610101D01*
X2122288Y1608935D01*
X2122943Y1607185D01*
Y1599018D01*
G01X2134985Y1593185D02*
X2137168Y1596101D01*
X2138260Y1599018D01*
Y1610684D01*
X2137168Y1613601D01*
X2134985Y1616518D01*
G01X1987108Y1636001D02*
X1988855Y1634543D01*
X1990820Y1633668D01*
X1992566D01*
X1994313Y1634543D01*
X1995623Y1636001D01*
X1996278Y1638043D01*
X1995841Y1640084D01*
X1994750Y1641835D01*
X1992785Y1643001D01*
X1990165Y1643585D01*
X1988636Y1644751D01*
X1987981Y1646793D01*
X1988418Y1648835D01*
X1989510Y1650293D01*
X1991038Y1651168D01*
X1992566D01*
X1994095Y1650585D01*
X1995405Y1649126D01*
G01X2013560Y1633668D02*
X2004826D01*
Y1651168D01*
X2013560D01*
G01X2010066Y1642710D02*
X2004826D01*
G01X2041573Y1651168D02*
X2046813D01*
G01X2044193D02*
Y1633668D01*
G01X2041573D02*
X2046813D01*
G01X2056016D02*
Y1651168D01*
X2061693Y1636585D01*
X2067370Y1651168D01*
Y1633668D01*
G01X2074826D02*
Y1651168D01*
X2080066D01*
X2081813Y1650293D01*
X2083123Y1648251D01*
X2083560Y1645918D01*
X2083123Y1643585D01*
X2082031Y1641835D01*
X2080066Y1640959D01*
X2074826D01*
G01X2101060Y1633668D02*
X2092326D01*
Y1651168D01*
X2101060D01*
G01X2097566Y1642710D02*
X2092326D01*
G01X2109390Y1633668D02*
Y1651168D01*
X2113756D01*
X2115503Y1650293D01*
X2116813Y1649126D01*
X2117905Y1647377D01*
X2118778Y1645334D01*
X2118996Y1642418D01*
X2118778Y1639501D01*
X2117905Y1637459D01*
X2116813Y1635709D01*
X2115503Y1634543D01*
X2113756Y1633668D01*
X2109390D01*
G01X2126234D02*
X2131693Y1651168D01*
X2137152Y1633668D01*
G01X2135186Y1639793D02*
X2128199D01*
G01X2144171Y1633668D02*
Y1651168D01*
X2154215Y1633668D01*
Y1651168D01*
G01X2171496Y1649709D02*
X2170186Y1650585D01*
X2168658Y1651168D01*
X2166911D01*
X2164946Y1650293D01*
X2163418Y1648835D01*
X2162326Y1647084D01*
X2161453Y1644168D01*
X2161234Y1641543D01*
X2161671Y1638918D01*
X2162326Y1637168D01*
X2163636Y1635418D01*
X2165165Y1634251D01*
X2166693Y1633668D01*
X2168221D01*
X2169750Y1634251D01*
X2171060Y1635126D01*
X2172152Y1636292D01*
G01X2188560Y1633668D02*
X2179826D01*
Y1651168D01*
X2188560D01*
G01X2185066Y1642710D02*
X2179826D01*
G01X2219193Y1651168D02*
Y1633668D01*
G01X2214171Y1651168D02*
X2224215D01*
G01X2231234Y1633668D02*
X2236693Y1651168D01*
X2242152Y1633668D01*
G01X2240186Y1639793D02*
X2233199D01*
G01X2255939Y1643001D02*
X2256813Y1643876D01*
X2257468Y1645334D01*
X2257905Y1647377D01*
X2257468Y1649126D01*
X2256595Y1650293D01*
X2255066Y1651168D01*
X2249171D01*
Y1633668D01*
X2256376D01*
X2257905Y1634834D01*
X2258778Y1636585D01*
X2259215Y1638626D01*
X2258778Y1640668D01*
X2257468Y1642418D01*
X2255939Y1643001D01*
X2249171D01*
G01X2267326Y1651168D02*
Y1633668D01*
X2276060D01*
G01X2293560D02*
X2284826D01*
Y1651168D01*
X2293560D01*
G01X2290066Y1642710D02*
X2284826D01*
G01X2306693Y1633085D02*
X2306256Y1633376D01*
Y1633960D01*
X2306693Y1634251D01*
X2307130Y1633960D01*
Y1633376D01*
X2306693Y1633085D01*
G01Y1640959D02*
X2306256Y1641251D01*
Y1641835D01*
X2306693Y1642126D01*
X2307130Y1641835D01*
Y1641251D01*
X2306693Y1640959D01*
G01X2337326Y1651168D02*
Y1633668D01*
X2346060D01*
G01X2359193D02*
Y1651168D01*
X2356573Y1647668D01*
G01Y1633668D02*
X2361813D01*
G01X2376693Y1651168D02*
X2374946Y1650585D01*
X2373636Y1649126D01*
X2372763Y1647377D01*
X2372108Y1645043D01*
X2371890Y1642418D01*
X2372108Y1639793D01*
X2372763Y1637459D01*
X2373636Y1635709D01*
X2374946Y1634251D01*
X2376693Y1633668D01*
X2378439Y1634251D01*
X2379750Y1635709D01*
X2380623Y1637459D01*
X2381278Y1639793D01*
X2381496Y1642418D01*
X2381278Y1645043D01*
X2380623Y1647377D01*
X2379750Y1649126D01*
X2378439Y1650585D01*
X2376693Y1651168D01*
G01X2041590Y1566992D02*
X2042899Y1565534D01*
X2044428Y1564660D01*
X2046393Y1564368D01*
X2048358Y1564951D01*
X2049886Y1566118D01*
X2050978Y1568159D01*
X2051196Y1570493D01*
X2050760Y1572826D01*
X2049668Y1574285D01*
X2048139Y1575451D01*
X2046611Y1575743D01*
X2045083Y1575451D01*
X2043118Y1574285D01*
X2043773Y1581868D01*
X2049668D01*
G01X2063893D02*
X2062146Y1581285D01*
X2060836Y1579826D01*
X2059963Y1578077D01*
X2059308Y1575743D01*
X2059090Y1573118D01*
X2059308Y1570493D01*
X2059963Y1568159D01*
X2060836Y1566409D01*
X2062146Y1564951D01*
X2063893Y1564368D01*
X2065639Y1564951D01*
X2066950Y1566409D01*
X2067823Y1568159D01*
X2068478Y1570493D01*
X2068696Y1573118D01*
X2068478Y1575743D01*
X2067823Y1578077D01*
X2066950Y1579826D01*
X2065639Y1581285D01*
X2063893Y1581868D01*
G01X2081393Y1563785D02*
X2080956Y1564076D01*
Y1564660D01*
X2081393Y1564951D01*
X2081830Y1564660D01*
Y1564076D01*
X2081393Y1563785D01*
G01X2098893Y1581868D02*
X2097146Y1581285D01*
X2095836Y1579826D01*
X2094963Y1578077D01*
X2094308Y1575743D01*
X2094090Y1573118D01*
X2094308Y1570493D01*
X2094963Y1568159D01*
X2095836Y1566409D01*
X2097146Y1564951D01*
X2098893Y1564368D01*
X2100639Y1564951D01*
X2101950Y1566409D01*
X2102823Y1568159D01*
X2103478Y1570493D01*
X2103696Y1573118D01*
X2103478Y1575743D01*
X2102823Y1578077D01*
X2101950Y1579826D01*
X2100639Y1581285D01*
X2098893Y1581868D01*
G01X2197343Y1616518D02*
X2200399Y1599018D01*
X2203893Y1616518D01*
X2207386Y1599018D01*
X2210443Y1616518D01*
G01X2218773D02*
X2224013D01*
G01X2221393D02*
Y1599018D01*
G01X2218773D02*
X2224013D01*
G01X2234090D02*
Y1616518D01*
X2238456D01*
X2240203Y1615643D01*
X2241513Y1614476D01*
X2242605Y1612727D01*
X2243478Y1610684D01*
X2243696Y1607768D01*
X2243478Y1604851D01*
X2242605Y1602809D01*
X2241513Y1601059D01*
X2240203Y1599893D01*
X2238456Y1599018D01*
X2234090D01*
G01X2256393Y1616518D02*
Y1599018D01*
G01X2251371Y1616518D02*
X2261415D01*
G01X2269308Y1599018D02*
Y1616518D01*
G01X2278478D02*
Y1599018D01*
G01Y1607768D02*
X2269308D01*
G01X2290301Y1593185D02*
X2288118Y1596101D01*
X2287026Y1599018D01*
Y1610684D01*
X2288118Y1613601D01*
X2290301Y1616518D01*
G01X2302343Y1599018D02*
Y1610684D01*
G01Y1607476D02*
X2302998Y1608935D01*
X2304090Y1610101D01*
X2305618Y1610684D01*
X2307146Y1610101D01*
X2308238Y1608935D01*
X2308893Y1607476D01*
Y1599018D01*
G01Y1607476D02*
X2309548Y1608935D01*
X2310639Y1610101D01*
X2312168Y1610684D01*
X2313696Y1610101D01*
X2314788Y1608935D01*
X2315443Y1607185D01*
Y1599018D01*
G01X2326393Y1610684D02*
Y1599018D01*
G01Y1615351D02*
X2325956Y1615643D01*
Y1616226D01*
X2326393Y1616518D01*
X2326830Y1616226D01*
Y1615643D01*
X2326393Y1615351D01*
G01X2343893Y1599018D02*
Y1616518D01*
G01X2358118Y1601059D02*
X2359210Y1599893D01*
X2360738Y1599018D01*
X2362048D01*
X2363358Y1599601D01*
X2364231Y1600476D01*
X2364668Y1601642D01*
X2364450Y1603393D01*
X2363576Y1604268D01*
X2359646Y1606018D01*
X2358773Y1608060D01*
X2359210Y1609518D01*
X2360083Y1610393D01*
X2361393Y1610684D01*
X2362703Y1610393D01*
X2364013Y1609518D01*
G01X2379985Y1593185D02*
X2382168Y1596101D01*
X2383260Y1599018D01*
Y1610684D01*
X2382168Y1613601D01*
X2379985Y1616518D01*
G01X2260340Y1566992D02*
X2261649Y1565534D01*
X2263178Y1564660D01*
X2265143Y1564368D01*
X2267108Y1564951D01*
X2268636Y1566118D01*
X2269728Y1568159D01*
X2269946Y1570493D01*
X2269510Y1572826D01*
X2268418Y1574285D01*
X2266889Y1575451D01*
X2265361Y1575743D01*
X2263833Y1575451D01*
X2261868Y1574285D01*
X2262523Y1581868D01*
X2268418D01*
G01X2282643Y1563785D02*
X2282206Y1564076D01*
Y1564660D01*
X2282643Y1564951D01*
X2283080Y1564660D01*
Y1564076D01*
X2282643Y1563785D01*
G01X2295995Y1578951D02*
X2297305Y1580701D01*
X2298833Y1581576D01*
X2300580Y1581868D01*
X2302763Y1581285D01*
X2304291Y1579826D01*
X2304728Y1578077D01*
X2304510Y1576326D01*
X2303636Y1574868D01*
X2299270Y1571951D01*
X2297305Y1569910D01*
X2295995Y1566992D01*
X2295558Y1564368D01*
X2304728D01*
G01X2312840Y1566992D02*
X2314149Y1565534D01*
X2315678Y1564660D01*
X2317643Y1564368D01*
X2319608Y1564951D01*
X2321136Y1566118D01*
X2322228Y1568159D01*
X2322446Y1570493D01*
X2322010Y1572826D01*
X2320918Y1574285D01*
X2319389Y1575451D01*
X2317861Y1575743D01*
X2316333Y1575451D01*
X2314368Y1574285D01*
X2315023Y1581868D01*
X2320918D01*
G01X2461808Y1566701D02*
X2463555Y1565243D01*
X2465520Y1564368D01*
X2467266D01*
X2469013Y1565243D01*
X2470323Y1566701D01*
X2470978Y1568743D01*
X2470541Y1570784D01*
X2469450Y1572535D01*
X2467485Y1573701D01*
X2464865Y1574285D01*
X2463336Y1575451D01*
X2462681Y1577493D01*
X2463118Y1579535D01*
X2464210Y1580993D01*
X2465738Y1581868D01*
X2467266D01*
X2468795Y1581285D01*
X2470105Y1579826D01*
G01X2488260Y1564368D02*
X2479526D01*
Y1581868D01*
X2488260D01*
G01X2484766Y1573410D02*
X2479526D01*
G01X2448893Y1616518D02*
Y1599018D01*
G01X2443871Y1616518D02*
X2453915D01*
G01X2466393Y1599018D02*
Y1606893D01*
X2462026Y1616518D01*
G01X2470760D02*
X2466393Y1606893D01*
G01X2479526Y1599018D02*
Y1616518D01*
X2484766D01*
X2486513Y1615643D01*
X2487823Y1613601D01*
X2488260Y1611268D01*
X2487823Y1608935D01*
X2486731Y1607185D01*
X2484766Y1606309D01*
X2479526D01*
G01X2505760Y1599018D02*
X2497026D01*
Y1616518D01*
X2505760D01*
G01X2502266Y1608060D02*
X2497026D01*
G01X2584526Y1581868D02*
Y1564368D01*
X2593260D01*
G01X2602681Y1566409D02*
X2604210Y1564951D01*
X2605956Y1564368D01*
X2607703Y1564951D01*
X2609231Y1566701D01*
X2610323Y1569326D01*
X2610760Y1571951D01*
Y1575159D01*
X2610323Y1577784D01*
X2609231Y1580118D01*
X2607921Y1581285D01*
X2606393Y1581868D01*
X2604646Y1581285D01*
X2603336Y1580118D01*
X2602463Y1578368D01*
X2602026Y1576034D01*
X2602463Y1573993D01*
X2603555Y1571951D01*
X2604865Y1570784D01*
X2606393Y1570493D01*
X2608139Y1571076D01*
X2609450Y1572535D01*
X2610760Y1575159D01*
G01X2619963Y1563785D02*
X2627823Y1581868D01*
G01X2637026D02*
Y1564368D01*
X2645760D01*
G01X2658893D02*
Y1581868D01*
X2656273Y1578368D01*
G01Y1564368D02*
X2661513D01*
G01X2676393D02*
Y1581868D01*
X2673773Y1578368D01*
G01Y1564368D02*
X2679013D01*
G01X2549526Y1599018D02*
Y1616518D01*
X2554985D01*
X2556731Y1615643D01*
X2557823Y1614476D01*
X2558260Y1612143D01*
X2557823Y1609809D01*
X2556513Y1608351D01*
X2554985Y1607476D01*
X2549526D01*
G01X2554985D02*
X2558260Y1599018D01*
G01X2568118Y1606893D02*
X2575105D01*
X2574450Y1608935D01*
X2573358Y1610101D01*
X2571830Y1610684D01*
X2570301Y1610393D01*
X2568991Y1609518D01*
X2568118Y1607476D01*
X2567681Y1605726D01*
Y1603976D01*
X2568118Y1602226D01*
X2569210Y1600476D01*
X2570520Y1599310D01*
X2572048Y1599018D01*
X2573576Y1599601D01*
X2575105Y1601351D01*
G01X2587583Y1599018D02*
Y1613893D01*
X2588020Y1615351D01*
X2588893Y1616226D01*
X2590203Y1616518D01*
X2591513Y1615935D01*
X2592168Y1614476D01*
G01X2589548Y1609518D02*
X2585181D01*
G01X2606393Y1598435D02*
X2605956Y1598726D01*
Y1599310D01*
X2606393Y1599601D01*
X2606830Y1599310D01*
Y1598726D01*
X2606393Y1598435D01*
G01X2637026Y1599018D02*
Y1616518D01*
X2642266D01*
X2644013Y1615643D01*
X2645323Y1613601D01*
X2645760Y1611268D01*
X2645323Y1608935D01*
X2644231Y1607185D01*
X2642266Y1606309D01*
X2637026D01*
G01X2658893Y1599018D02*
Y1616518D01*
G01X2680323Y1599018D02*
Y1610684D01*
G01Y1608643D02*
X2679450Y1609809D01*
X2678139Y1610393D01*
X2676611Y1610684D01*
X2675083Y1610101D01*
X2673773Y1608935D01*
X2672899Y1607185D01*
X2672463Y1604851D01*
X2672899Y1602518D01*
X2673773Y1600768D01*
X2675083Y1599601D01*
X2676611Y1599018D01*
X2678139Y1599310D01*
X2679450Y1600184D01*
X2680323Y1601351D01*
G01X2690181Y1599018D02*
Y1610684D01*
G01Y1607768D02*
X2691055Y1609226D01*
X2692365Y1610393D01*
X2694111Y1610684D01*
X2695639Y1610393D01*
X2696950Y1609226D01*
X2697605Y1607185D01*
Y1599018D01*
G01X2708118Y1606893D02*
X2715105D01*
X2714450Y1608935D01*
X2713358Y1610101D01*
X2711830Y1610684D01*
X2710301Y1610393D01*
X2708991Y1609518D01*
X2708118Y1607476D01*
X2707681Y1605726D01*
Y1603976D01*
X2708118Y1602226D01*
X2709210Y1600476D01*
X2710520Y1599310D01*
X2712048Y1599018D01*
X2713576Y1599601D01*
X2715105Y1601351D01*
G01X2829193Y1576034D02*
Y1564368D01*
G01Y1580701D02*
X2828756Y1580993D01*
Y1581576D01*
X2829193Y1581868D01*
X2829630Y1581576D01*
Y1580993D01*
X2829193Y1580701D01*
G01X2843418Y1566409D02*
X2844510Y1565243D01*
X2846038Y1564368D01*
X2847348D01*
X2848658Y1564951D01*
X2849531Y1565826D01*
X2849968Y1566992D01*
X2849750Y1568743D01*
X2848876Y1569618D01*
X2844946Y1571368D01*
X2844073Y1573410D01*
X2844510Y1574868D01*
X2845383Y1575743D01*
X2846693Y1576034D01*
X2848003Y1575743D01*
X2849313Y1574868D01*
G01X2876671Y1564368D02*
Y1581868D01*
X2886715Y1564368D01*
Y1581868D01*
G01X2899193Y1564368D02*
X2897446Y1564660D01*
X2895918Y1565826D01*
X2894608Y1567576D01*
X2893734Y1569618D01*
X2893298Y1571951D01*
Y1574285D01*
X2893734Y1576618D01*
X2894608Y1578660D01*
X2895918Y1580409D01*
X2897446Y1581576D01*
X2899193Y1581868D01*
X2900939Y1581576D01*
X2902468Y1580409D01*
X2903778Y1578660D01*
X2904652Y1576618D01*
X2905088Y1574285D01*
Y1571951D01*
X2904652Y1569618D01*
X2903778Y1567576D01*
X2902468Y1565826D01*
X2900939Y1564660D01*
X2899193Y1564368D01*
G01X2916693Y1581868D02*
Y1564368D01*
G01X2911671Y1581868D02*
X2921715D01*
G01X2947981Y1576034D02*
Y1567868D01*
X2948855Y1565826D01*
X2950165Y1564660D01*
X2951693Y1564368D01*
X2953221Y1564660D01*
X2954531Y1565826D01*
X2955405Y1567868D01*
G01Y1564368D02*
Y1576034D01*
G01X2965918Y1566409D02*
X2967010Y1565243D01*
X2968538Y1564368D01*
X2969848D01*
X2971158Y1564951D01*
X2972031Y1565826D01*
X2972468Y1566992D01*
X2972250Y1568743D01*
X2971376Y1569618D01*
X2967446Y1571368D01*
X2966573Y1573410D01*
X2967010Y1574868D01*
X2967883Y1575743D01*
X2969193Y1576034D01*
X2970503Y1575743D01*
X2971813Y1574868D01*
G01X2983418Y1572243D02*
X2990405D01*
X2989750Y1574285D01*
X2988658Y1575451D01*
X2987130Y1576034D01*
X2985601Y1575743D01*
X2984291Y1574868D01*
X2983418Y1572826D01*
X2982981Y1571076D01*
Y1569326D01*
X2983418Y1567576D01*
X2984510Y1565826D01*
X2985820Y1564660D01*
X2987348Y1564368D01*
X2988876Y1564951D01*
X2990405Y1566701D01*
G01X3008123Y1581868D02*
Y1564368D01*
G01Y1566992D02*
X3007250Y1565534D01*
X3005939Y1564660D01*
X3004411Y1564368D01*
X3002665Y1564951D01*
X3001355Y1566409D01*
X3000481Y1568159D01*
X3000263Y1570201D01*
X3000481Y1572243D01*
X3001355Y1573993D01*
X3002665Y1575451D01*
X3004411Y1576034D01*
X3005939Y1575743D01*
X3007031Y1575159D01*
X3008123Y1573993D01*
G01X2754390Y1598435D02*
X2763996Y1611268D01*
G01X2759193Y1613601D02*
Y1596101D01*
G01X2763996Y1598435D02*
X2754390Y1611268D01*
G01X2752643Y1604851D02*
X2765743D01*
G01X2791355D02*
X2797031D01*
G01X2824390Y1599018D02*
Y1616518D01*
X2828756D01*
X2830503Y1615643D01*
X2831813Y1614476D01*
X2832905Y1612727D01*
X2833778Y1610684D01*
X2833996Y1607768D01*
X2833778Y1604851D01*
X2832905Y1602809D01*
X2831813Y1601059D01*
X2830503Y1599893D01*
X2828756Y1599018D01*
X2824390D01*
G01X2843418Y1606893D02*
X2850405D01*
X2849750Y1608935D01*
X2848658Y1610101D01*
X2847130Y1610684D01*
X2845601Y1610393D01*
X2844291Y1609518D01*
X2843418Y1607476D01*
X2842981Y1605726D01*
Y1603976D01*
X2843418Y1602226D01*
X2844510Y1600476D01*
X2845820Y1599310D01*
X2847348Y1599018D01*
X2848876Y1599601D01*
X2850405Y1601351D01*
G01X2860481Y1599018D02*
Y1610684D01*
G01Y1607768D02*
X2861355Y1609226D01*
X2862665Y1610393D01*
X2864411Y1610684D01*
X2865939Y1610393D01*
X2867250Y1609226D01*
X2867905Y1607185D01*
Y1599018D01*
G01X2881693D02*
X2880383Y1599310D01*
X2879073Y1600476D01*
X2878199Y1602518D01*
X2877763Y1604851D01*
X2878199Y1607185D01*
X2879073Y1609226D01*
X2880383Y1610393D01*
X2881693Y1610684D01*
X2883003Y1610393D01*
X2884313Y1609226D01*
X2885186Y1607185D01*
X2885405Y1604851D01*
X2885186Y1602518D01*
X2884313Y1600476D01*
X2883003Y1599310D01*
X2881693Y1599018D01*
G01X2899193Y1616518D02*
Y1599018D01*
G01X2896136Y1610684D02*
X2902250D01*
G01X2913418Y1606893D02*
X2920405D01*
X2919750Y1608935D01*
X2918658Y1610101D01*
X2917130Y1610684D01*
X2915601Y1610393D01*
X2914291Y1609518D01*
X2913418Y1607476D01*
X2912981Y1605726D01*
Y1603976D01*
X2913418Y1602226D01*
X2914510Y1600476D01*
X2915820Y1599310D01*
X2917348Y1599018D01*
X2918876Y1599601D01*
X2920405Y1601351D01*
G01X2930918Y1601059D02*
X2932010Y1599893D01*
X2933538Y1599018D01*
X2934848D01*
X2936158Y1599601D01*
X2937031Y1600476D01*
X2937468Y1601642D01*
X2937250Y1603393D01*
X2936376Y1604268D01*
X2932446Y1606018D01*
X2931573Y1608060D01*
X2932010Y1609518D01*
X2932883Y1610393D01*
X2934193Y1610684D01*
X2935503Y1610393D01*
X2936813Y1609518D01*
G01X2969193Y1616518D02*
Y1599018D01*
G01X2966136Y1610684D02*
X2972250D01*
G01X2982981Y1599018D02*
Y1616518D01*
G01Y1608060D02*
X2984073Y1609518D01*
X2985165Y1610393D01*
X2986911Y1610684D01*
X2988221Y1610393D01*
X2989750Y1609226D01*
X2990405Y1607476D01*
Y1599018D01*
G01X3008123D02*
Y1610684D01*
G01Y1608643D02*
X3007250Y1609809D01*
X3005939Y1610393D01*
X3004411Y1610684D01*
X3002883Y1610101D01*
X3001573Y1608935D01*
X3000699Y1607185D01*
X3000263Y1604851D01*
X3000699Y1602518D01*
X3001573Y1600768D01*
X3002883Y1599601D01*
X3004411Y1599018D01*
X3005939Y1599310D01*
X3007250Y1600184D01*
X3008123Y1601351D01*
G01X3021693Y1616518D02*
Y1599018D01*
G01X3018636Y1610684D02*
X3024750D01*
G01X3056693Y1616518D02*
Y1599018D01*
G01X3053636Y1610684D02*
X3059750D01*
G01X3070481Y1599018D02*
Y1616518D01*
G01Y1608060D02*
X3071573Y1609518D01*
X3072665Y1610393D01*
X3074411Y1610684D01*
X3075721Y1610393D01*
X3077250Y1609226D01*
X3077905Y1607476D01*
Y1599018D01*
G01X3091693Y1610684D02*
Y1599018D01*
G01Y1615351D02*
X3091256Y1615643D01*
Y1616226D01*
X3091693Y1616518D01*
X3092130Y1616226D01*
Y1615643D01*
X3091693Y1615351D01*
G01X3105918Y1601059D02*
X3107010Y1599893D01*
X3108538Y1599018D01*
X3109848D01*
X3111158Y1599601D01*
X3112031Y1600476D01*
X3112468Y1601642D01*
X3112250Y1603393D01*
X3111376Y1604268D01*
X3107446Y1606018D01*
X3106573Y1608060D01*
X3107010Y1609518D01*
X3107883Y1610393D01*
X3109193Y1610684D01*
X3110503Y1610393D01*
X3111813Y1609518D01*
G01X3141573Y1616518D02*
X3146813D01*
G01X3144193D02*
Y1599018D01*
G01X3141573D02*
X3146813D01*
G01X3155143D02*
Y1610684D01*
G01Y1607476D02*
X3155798Y1608935D01*
X3156890Y1610101D01*
X3158418Y1610684D01*
X3159946Y1610101D01*
X3161038Y1608935D01*
X3161693Y1607476D01*
Y1599018D01*
G01Y1607476D02*
X3162348Y1608935D01*
X3163439Y1610101D01*
X3164968Y1610684D01*
X3166496Y1610101D01*
X3167588Y1608935D01*
X3168243Y1607185D01*
Y1599018D01*
G01X3175263Y1593185D02*
Y1610684D01*
G01Y1608060D02*
X3176355Y1609518D01*
X3177446Y1610393D01*
X3179193Y1610684D01*
X3180721Y1610393D01*
X3182250Y1608935D01*
X3182905Y1606893D01*
X3183123Y1604851D01*
X3182905Y1602809D01*
X3182250Y1600768D01*
X3180939Y1599601D01*
X3179193Y1599018D01*
X3177665Y1599310D01*
X3176136Y1600184D01*
X3175263Y1601351D01*
G01X3193418Y1606893D02*
X3200405D01*
X3199750Y1608935D01*
X3198658Y1610101D01*
X3197130Y1610684D01*
X3195601Y1610393D01*
X3194291Y1609518D01*
X3193418Y1607476D01*
X3192981Y1605726D01*
Y1603976D01*
X3193418Y1602226D01*
X3194510Y1600476D01*
X3195820Y1599310D01*
X3197348Y1599018D01*
X3198876Y1599601D01*
X3200405Y1601351D01*
G01X3218123Y1616518D02*
Y1599018D01*
G01Y1601642D02*
X3217250Y1600184D01*
X3215939Y1599310D01*
X3214411Y1599018D01*
X3212665Y1599601D01*
X3211355Y1601059D01*
X3210481Y1602809D01*
X3210263Y1604851D01*
X3210481Y1606893D01*
X3211355Y1608643D01*
X3212665Y1610101D01*
X3214411Y1610684D01*
X3215939Y1610393D01*
X3217031Y1609809D01*
X3218123Y1608643D01*
G01X3235623Y1599018D02*
Y1610684D01*
G01Y1608643D02*
X3234750Y1609809D01*
X3233439Y1610393D01*
X3231911Y1610684D01*
X3230383Y1610101D01*
X3229073Y1608935D01*
X3228199Y1607185D01*
X3227763Y1604851D01*
X3228199Y1602518D01*
X3229073Y1600768D01*
X3230383Y1599601D01*
X3231911Y1599018D01*
X3233439Y1599310D01*
X3234750Y1600184D01*
X3235623Y1601351D01*
G01X3245481Y1599018D02*
Y1610684D01*
G01Y1607768D02*
X3246355Y1609226D01*
X3247665Y1610393D01*
X3249411Y1610684D01*
X3250939Y1610393D01*
X3252250Y1609226D01*
X3252905Y1607185D01*
Y1599018D01*
G01X3270186Y1609226D02*
X3268658Y1610393D01*
X3267348Y1610684D01*
X3265601Y1610101D01*
X3264291Y1608935D01*
X3263418Y1606893D01*
X3263199Y1604851D01*
X3263418Y1602809D01*
X3264291Y1601059D01*
X3265601Y1599601D01*
X3267348Y1599018D01*
X3268876Y1599601D01*
X3270186Y1600768D01*
G01X3280918Y1606893D02*
X3287905D01*
X3287250Y1608935D01*
X3286158Y1610101D01*
X3284630Y1610684D01*
X3283101Y1610393D01*
X3281791Y1609518D01*
X3280918Y1607476D01*
X3280481Y1605726D01*
Y1603976D01*
X3280918Y1602226D01*
X3282010Y1600476D01*
X3283320Y1599310D01*
X3284848Y1599018D01*
X3286376Y1599601D01*
X3287905Y1601351D01*
G01X0Y-137756D02*
G03X15000Y-152756I15000J0D01*
G01X0Y-137756D02*
G03X15000Y-152756I15000J0D01*
G01X0Y-11811D02*
Y-137756D01*
G01Y-11811D02*
Y-137756D01*
G01X854331Y-152756D02*
X15000D01*
G01X854331D02*
X15000D01*
G01X23622Y-7874D02*
G03Y0I0J3937D01*
G01Y-7874D02*
G03Y0I0J3937D01*
G01X0Y3937D02*
G03X3937Y0I3937J0D01*
G01Y-7874D02*
X23622D01*
G01X0Y3937D02*
G03X3937Y0I3937J0D01*
G01Y-7874D02*
X23622D01*
G01X3937D02*
G03X0Y-11811I0J-3937D01*
G01X3937Y-7874D02*
G03X0Y-11811I0J-3937D01*
G01X3937Y0D02*
X397638D01*
G01X3937D02*
X397638D01*
G01X0Y1370866D02*
Y3937D01*
G01Y1370866D02*
Y3937D01*
G01X3937Y1374803D02*
G03X0Y1370866I0J-3937D01*
G01X3937Y1374803D02*
G03X0Y1370866I0J-3937D01*
G01X23622Y1374803D02*
G03Y1382677I0J3937D01*
G01Y1374803D02*
G03Y1382677I0J3937D01*
G01X3937D02*
X23622D01*
G01X0Y1386614D02*
G03X3937Y1382677I3937J0D01*
G01D02*
X23622D01*
G01X0Y1386614D02*
G03X3937Y1382677I3937J0D01*
G01Y1374803D02*
X746850D01*
G01D02*
X3937D01*
G01X0Y1386614D02*
Y1643268D01*
G01Y1386614D02*
Y1643268D01*
G01X15000Y1658268D02*
G03X0Y1643268I0J-15000D01*
G01X15000Y1658268D02*
G03X0Y1643268I0J-15000D01*
G01X775591Y1658268D02*
X15000D01*
G01X775591D02*
X15000D01*
G01X54331Y-7874D02*
X323228D01*
G01X54331D02*
X323228D01*
G01X54331Y0D02*
G03Y-7874I0J-3937D01*
G01Y0D02*
G03Y-7874I0J-3937D01*
G01Y1382677D02*
G03Y1374803I0J-3937D01*
G01Y1382677D02*
G03Y1374803I0J-3937D01*
G01Y1382677D02*
X353740D01*
G01X54331D02*
X353740D01*
G01X114295Y378885D02*
G03X148106I16905J-13531D01*
G01X114295D02*
G03X148106I16905J-13531D01*
G01X114295D02*
G03X121220Y392016I-30737J24602D01*
G01X114295Y378885D02*
G03X121220Y392016I-30737J24602D01*
G01X114295Y831641D02*
G03X121220Y844772I-30737J24601D01*
G01X114295Y831641D02*
G03X121220Y844772I-30737J24602D01*
G01X114295Y831641D02*
G03X148106I16905J-13531D01*
G01X114295D02*
G03X148106I16905J-13531D01*
G01X114295Y1284397D02*
G03X148106I16905J-13531D01*
G01X114295D02*
G03X148106I16905J-13531D01*
G01X114295D02*
G03X121220Y1297528I-30737J24601D01*
G01X114295Y1284397D02*
G03X121220Y1297528I-30737J24602D01*
G01X141181Y392016D02*
G03X121220I-9980J-3039D01*
G01X141181D02*
G03X148106Y378885I37662J11471D01*
G01X141181Y392016D02*
G03X121220I-9980J-3039D01*
G01X141181D02*
G03X148106Y378885I37662J11471D01*
G01X141181Y844772D02*
G03X148106Y831641I37662J11471D01*
G01X141181Y844772D02*
G03X148106Y831641I37662J11471D01*
G01X141181Y844772D02*
G03X121220I-9980J-3040D01*
G01X141181D02*
G03X121220I-9980J-3039D01*
G01X141181Y1297528D02*
G03X121220I-9980J-3040D01*
G01X141181D02*
G03X148106Y1284397I37662J11471D01*
G01X141181Y1297528D02*
G03X121220I-9980J-3040D01*
G01X141181D02*
G03X148106Y1284397I37662J11471D01*
G01X323228Y-7874D02*
G03Y0I0J3937D01*
G01Y-7874D02*
G03Y0I0J3937D01*
G01X362598D02*
G03Y-7874I0J-3937D01*
G01Y0D02*
G03Y-7874I0J-3937D01*
G01X362327Y378885D02*
G03X396138I16905J-13531D01*
G01X362327D02*
G03X396138I16905J-13531D01*
G01X362327D02*
G03X369252Y392016I-30737J24602D01*
G01X362327Y378885D02*
G03X369252Y392016I-30737J24602D01*
G01X362327Y831641D02*
G03X369252Y844772I-30737J24602D01*
G01X362327Y831641D02*
G03X369252Y844772I-30737J24602D01*
G01X362327Y831641D02*
G03X396138I16905J-13531D01*
G01X362327D02*
G03X396138I16905J-13531D01*
G01X362327Y1284397D02*
G03X396138I16905J-13531D01*
G01X362327D02*
G03X396138I16905J-13531D01*
G01X362327D02*
G03X369252Y1297528I-30737J24602D01*
G01X362327Y1284397D02*
G03X369252Y1297528I-30737J24602D01*
G01X353740Y1374803D02*
G03Y1382677I0J3937D01*
G01Y1374803D02*
G03Y1382677I0J3937D01*
G01X401575Y3937D02*
Y55118D01*
G01X397638Y0D02*
G03X401575Y3937I0J3937D01*
G01X409449D02*
Y51181D01*
G01X397638Y-7874D02*
G03X409449Y3937I0J11811D01*
G01X397638Y0D02*
G03X401575Y3937I0J3937D01*
G01D02*
Y55118D01*
G01X409449Y3937D02*
Y51181D01*
G01X397638Y-7874D02*
G03X409449Y3937I0J11811D01*
G01X362598Y-7874D02*
X397638D01*
G01X362598D02*
X397638D01*
G01X405512Y59055D02*
G03X401575Y55118I0J-3937D01*
G01X405512Y59055D02*
G03X401575Y55118I0J-3937D01*
G01X405512Y59055D02*
X586614D01*
G01X409449Y51181D02*
X582677D01*
G01X405512Y59055D02*
X586614D01*
G01X409449Y51181D02*
X582677D01*
G01X389213Y392016D02*
G03X396138Y378885I37662J11471D01*
G01X389213Y392016D02*
G03X396138Y378885I37662J11471D01*
G01X389213Y392016D02*
G03X369252I-9981J-3039D01*
G01X389213D02*
G03X369252I-9981J-3039D01*
G01X389213Y844772D02*
G03X396138Y831641I37662J11471D01*
G01X389213Y844772D02*
G03X396138Y831641I37662J11471D01*
G01X389213Y844772D02*
G03X369252I-9981J-3040D01*
G01X389213D02*
G03X369252I-9981J-3039D01*
G01X389213Y1297528D02*
G03X396138Y1284397I37662J11471D01*
G01X389213Y1297528D02*
G03X396138Y1284397I37662J11471D01*
G01X389213Y1297528D02*
G03X369252I-9981J-3040D01*
G01X389213D02*
G03X369252I-9981J-3040D01*
G01X393110Y1382677D02*
G03Y1374803I0J-3937D01*
G01Y1382677D02*
X692520D01*
G01X393110D02*
X692520D01*
G01X393110D02*
G03Y1374803I0J-3937D01*
G01X523327Y829921D02*
G03X483169I-20079J0D01*
G01X523327D02*
G03I-20079J0D01*
G01X483169D02*
G03X523327I20079J0D01*
G01X594488Y-7874D02*
X628765D01*
G01X594488D02*
X628765D01*
G01X590551Y55118D02*
Y3937D01*
G01D02*
G03X594488Y0I3937J0D01*
G01X582677Y51181D02*
Y3937D01*
G01D02*
G03X594488Y-7874I11811J0D01*
G01X590551Y55118D02*
Y3937D01*
G01D02*
G03X594488Y0I3937J0D01*
G01X582677Y51181D02*
Y3937D01*
G01D02*
G03X594488Y-7874I11811J0D01*
G01Y0D02*
X783465D01*
G01X594488D02*
X783465D01*
G01X590551Y55118D02*
G03X586614Y59055I-3937J0D01*
G01X590551Y55118D02*
G03X586614Y59055I-3937J0D01*
G01X628765Y-7874D02*
G03Y0I0J3937D01*
G01Y-7874D02*
G03Y0I0J3937D01*
G01X610358Y378885D02*
G03X644169I16906J-13531D01*
G01X610358D02*
G03X644169I16906J-13531D01*
G01X637244Y392016D02*
G03X644169Y378885I37662J11471D01*
G01X637244Y392016D02*
G03X644169Y378885I37662J11471D01*
G01X637244Y392016D02*
G03X617283I-9980J-3039D01*
G01X637244D02*
G03X617283I-9980J-3039D01*
G01X610358Y378885D02*
G03X617283Y392016I-30737J24602D01*
G01X610358Y378885D02*
G03X617283Y392016I-30737J24602D01*
G01X637244Y844772D02*
G03X644169Y831641I37662J11471D01*
G01X637244Y844772D02*
G03X644169Y831641I37662J11471D01*
G01X610358D02*
G03X617283Y844772I-30737J24601D01*
G01X610358Y831641D02*
G03X617283Y844772I-30737J24602D01*
G01X610358Y831641D02*
G03X644169I16906J-13531D01*
G01X610358D02*
G03X644169I16906J-13531D01*
G01X637244Y844772D02*
G03X617283I-9980J-3040D01*
G01X637244D02*
G03X617283I-9980J-3039D01*
G01X610358Y1284397D02*
G03X644169I16906J-13531D01*
G01X610358D02*
G03X644169I16906J-13531D01*
G01X637244Y1297528D02*
G03X644169Y1284397I37662J11471D01*
G01X637244Y1297528D02*
G03X644169Y1284397I37662J11471D01*
G01X610358D02*
G03X617283Y1297528I-30737J24601D01*
G01X637244D02*
G03X617283I-9980J-3040D01*
G01X610358Y1284397D02*
G03X617283Y1297528I-30737J24602D01*
G01X637244D02*
G03X617283I-9980J-3040D01*
G01X659474Y0D02*
G03Y-7874I0J-3937D01*
G01Y0D02*
G03Y-7874I0J-3937D01*
G01D02*
X780203D01*
G01X659474D02*
X780203D01*
G01X692520Y1374803D02*
G03Y1382677I0J3937D01*
G01Y1374803D02*
G03Y1382677I0J3937D01*
G01X746850Y1374803D02*
G03X750787Y1378740I0J3937D01*
G01X746850Y1374803D02*
G03X750787Y1378740I0J3937D01*
G01X723228Y1382677D02*
G03Y1374803I0J-3937D01*
G01Y1382677D02*
X742913D01*
G01X723228D02*
X742913D01*
G01X723228D02*
G03Y1374803I0J-3937D01*
G01X742913Y1464567D02*
Y1382677D01*
G01Y1464567D02*
Y1382677D01*
G01X754724Y1476378D02*
G03X742913Y1464567I0J-11811D01*
G01X754724Y1476378D02*
G03X742913Y1464567I0J-11811D01*
G01X862205Y-7874D02*
X791339D01*
G01X787402Y-3937D02*
G03X791339Y-7874I3937J0D01*
G01X787402Y-3937D02*
G03X791339Y-7874I3937J0D01*
G01D02*
X862205D01*
G01X858268Y-15748D02*
X791339D01*
G01X858268D02*
X791339D01*
G01X787402Y-3937D02*
G03X783465Y0I-3937J0D01*
G01X787402Y-3937D02*
G03X783465Y0I-3937J0D01*
G01X780203Y-7874D02*
G03X791339Y-15748I11136J3937D01*
G01X780203Y-7874D02*
G03X791339Y-15748I11136J3937D01*
G01X779551Y264712D02*
G03X813362I16905J-13531D01*
G01X779551D02*
G03X813362I16905J-13531D01*
G01X779551D02*
G03X786476Y277843I-30737J24601D01*
G01X806437D02*
G03X786476I-9981J-3040D01*
G01X779551Y264712D02*
G03X786476Y277843I-30737J24602D01*
G01X806437D02*
G03X786476I-9981J-3040D01*
G01X779551Y737153D02*
G03X786476Y750284I-30737J24601D01*
G01X779551Y737154D02*
G03X786476Y750284I-30736J24602D01*
G01X779551Y737153D02*
G03X813362I16905J-13531D01*
G01X779551D02*
G03X813362I16905J-13531D01*
G01X806437Y750284D02*
G03X786476I-9981J-3040D01*
G01X806437D02*
G03X786476I-9981J-3040D01*
G01X750787Y1464567D02*
Y1378740D01*
G01Y1464567D02*
Y1378740D01*
G01X783465Y1468504D02*
G03X787402Y1472441I0J3937D01*
G01X783465Y1468504D02*
G03X787402Y1472441I0J3937D01*
G01X783465Y1468504D02*
X754724D01*
G01D02*
G03X750787Y1464567I0J-3937D01*
G01X783465Y1468504D02*
X754724D01*
G01D02*
G03X750787Y1464567I0J-3937D01*
G01X779528Y1476378D02*
X754724D01*
G01X779528D02*
X754724D01*
G01X787402Y1654331D02*
Y1472441D01*
G01X779528Y1596063D02*
Y1476378D01*
G01X787402Y1654331D02*
Y1472441D01*
G01X779528Y1596063D02*
Y1476378D01*
G01X787402Y1596063D02*
G03X779528I-3937J0D01*
G01X787402D02*
G03X779528I-3937J0D01*
G01X1216535Y1658268D02*
X791339D01*
G01D02*
G03X787402Y1654331I0J-3937D01*
G01X779528D02*
G03X775591Y1658268I-3937J0D01*
G01X1216535D02*
X791339D01*
G01D02*
G03X787402Y1654331I0J-3937D01*
G01X779528D02*
G03X775591Y1658268I-3937J0D01*
G01X779528Y1654331D02*
Y1626772D01*
G01D02*
G03X787402I3937J0D01*
G01X779528Y1654331D02*
Y1626772D01*
G01D02*
G03X787402I3937J0D01*
G01X806437Y277843D02*
G03X813362Y264712I37662J11471D01*
G01X806437Y277843D02*
G03X813362Y264712I37662J11471D01*
G01X806437Y750284D02*
G03X813362Y737153I37662J11471D01*
G01X806437Y750284D02*
G03X813362Y737154I37661J11472D01*
G01X866142Y-148819D02*
Y-11811D01*
G01Y-148819D02*
G03X870079Y-152756I3937J0D01*
G01X866142Y-11811D02*
Y-148819D01*
G01D02*
G03X870079Y-152756I3937J0D01*
G01X866142Y-129134D02*
G03X858268I-3937J0D01*
G01X866142D02*
G03X858268I-3937J0D01*
G01Y-148819D02*
Y-129134D01*
G01X854331Y-152756D02*
G03X858268Y-148819I0J3937D01*
G01D02*
Y-129134D01*
G01X854331Y-152756D02*
G03X858268Y-148819I0J3937D01*
G01X1177165Y-152756D02*
X870079D01*
G01D02*
X1177165D01*
G01X858268Y-98425D02*
Y-15748D01*
G01Y-98425D02*
Y-15748D01*
G01Y-98425D02*
G03X866142I3937J0D01*
G01X858268D02*
G03X866142I3937J0D01*
G01Y-11811D02*
G03X862205Y-7874I-3937J0D01*
G01X866142Y-11811D02*
G03X862205Y-7874I-3937J0D01*
G01X927032Y-57820D02*
G03X962731I17850J-12259D01*
G01X927032Y-57821D02*
G03X962732I17850J-12258D01*
G01X927032Y-57820D02*
G03X935199Y-42571I-64908J44575D01*
G01X954565D02*
G03X935199I-9683J-3885D01*
G01X927032Y-57821D02*
G03X935199Y-42571I-64909J44573D01*
G01X954564D02*
G03X935199I-9682J-3885D01*
G01X944512Y1089122D02*
G03X978323I16905J-13531D01*
G01X944512Y1089121D02*
G03X978323I16905J-13531D01*
G01X944512Y1431641D02*
G03X978323I16905J-13531D01*
G01X944512D02*
G03X978323I16905J-13531D01*
G01X954565Y-42571D02*
G03X962731Y-57820I73077J29322D01*
G01X954564Y-42570D02*
G03X962732Y-57821I73076J29324D01*
G01X971398Y1102252D02*
G03X978323Y1089122I37661J11472D01*
G01X971398Y1102252D02*
G03X978323Y1089121I37662J11471D01*
G01X971398Y1102252D02*
G03X951437I-9980J-3039D01*
G01X971398D02*
G03X951437I-9980J-3039D01*
G01X944512Y1089122D02*
G03X951437Y1102252I-30737J24602D01*
G01X944512Y1089121D02*
G03X951437Y1102252I-30737J24602D01*
G01X971398Y1444772D02*
G03X978323Y1431641I37662J11471D01*
G01X971398Y1444772D02*
G03X978323Y1431641I37662J11471D01*
G01X971398Y1444772D02*
G03X951437I-9980J-3040D01*
G01X944512Y1431641D02*
G03X951437Y1444772I-30737J24602D01*
G01X944512Y1431641D02*
G03X951437Y1444772I-30737J24602D01*
G01X971398D02*
G03X951437I-9980J-3039D01*
G01X1181102Y-148819D02*
Y-3937D01*
G01X1177165Y-152756D02*
G03X1181102Y-148819I0J3937D01*
G01X1177165Y-152756D02*
G03X1181102Y-148819I0J3937D01*
G01D02*
Y-3937D01*
G01Y-94488D02*
G03X1188976I3937J0D01*
G01X1181102D02*
G03X1188976I3937J0D01*
G01Y-125197D02*
G03X1181102I-3937J0D01*
G01X1188976D02*
G03X1181102I-3937J0D01*
G01X1185039Y0D02*
G03X1181102Y-3937I0J-3937D01*
G01X1185039Y0D02*
G03X1181102Y-3937I0J-3937D01*
G01X1164984Y557626D02*
G03X1198795I16906J-13531D01*
G01X1164984Y557625D02*
G03X1198795I16906J-13531D01*
G01X1191870Y570756D02*
G03X1171909I-9980J-3039D01*
G01X1191870D02*
G03X1171909I-9980J-3039D01*
G01X1164984Y557626D02*
G03X1171909Y570756I-30736J24602D01*
G01X1164984Y557625D02*
G03X1171909Y570756I-30737J24602D01*
G01X1164984Y971011D02*
G03X1198795I16906J-13531D01*
G01X1164984D02*
G03X1198795I16906J-13531D01*
G01X1191870Y984142D02*
G03X1171909I-9980J-3040D01*
G01X1191870D02*
G03X1171909I-9980J-3039D01*
G01X1164984Y971011D02*
G03X1171909Y984142I-30737J24602D01*
G01X1164984Y971011D02*
G03X1171909Y984142I-30737J24602D01*
G01X1164173Y1378740D02*
Y1468504D01*
G01X1930906Y1374803D02*
X1168110D01*
G01X1164173Y1378740D02*
G03X1168110Y1374803I3937J0D01*
G01X1172047Y1382677D02*
Y1464567D01*
G01X1195669Y1382677D02*
X1172047D01*
G01X1930906Y1374803D02*
X1168110D01*
G01X1164173Y1378740D02*
G03X1168110Y1374804I3937J1D01*
G01X1164173Y1378740D02*
Y1468504D01*
G01X1172047Y1382677D02*
Y1464567D01*
G01X1195669Y1382677D02*
X1172047D01*
G01X1168110Y1472441D02*
G03X1164173Y1468504I0J-3937D01*
G01X1168110Y1472441D02*
G03X1164173Y1468504I0J-3937D01*
G01X1172047Y1464567D02*
X1216535D01*
G01X1172047D02*
X1216535D01*
G01X1168110Y1472441D02*
X1216535D01*
G01X1168110D02*
X1216535D01*
G01X1164984Y1561563D02*
G03X1171909Y1574693I-30736J24602D01*
G01X1164984Y1561562D02*
G03X1171909Y1574693I-30737J24602D01*
G01X1164984Y1561563D02*
G03X1198795I16906J-13531D01*
G01X1164984Y1561562D02*
G03X1198795I16906J-13531D01*
G01X1191870Y1574693D02*
G03X1171909I-9980J-3039D01*
G01X1191870D02*
G03X1171909I-9980J-3039D01*
G01X1188976Y-148819D02*
Y-125197D01*
G01Y-148819D02*
G03X1192913Y-152756I3937J0D01*
G01X1188976Y-148819D02*
Y-125197D01*
G01Y-148819D02*
G03X1192913Y-152756I3937J0D01*
G01D02*
X1919843D01*
G01X1192913D02*
X1919843D01*
G01X1188976Y-94488D02*
Y-7874D01*
G01Y-94488D02*
Y-7874D01*
G01X1185039Y0D02*
X1366142D01*
G01X1188976Y-7874D02*
X1315748D01*
G01X1185039Y0D02*
X1366142D01*
G01X1188976Y-7874D02*
X1315748D01*
G01X1191870Y570756D02*
G03X1198795Y557626I37662J11472D01*
G01X1191870Y570756D02*
G03X1198795Y557626I37662J11472D01*
G01X1191870Y984142D02*
G03X1198795Y971011I37662J11471D01*
G01X1191870Y984142D02*
G03X1198795Y971011I37662J11471D01*
G01X1524606Y1382677D02*
X1226378D01*
G01X1524606D02*
X1226378D01*
G01X1195669Y1374803D02*
G03Y1382677I0J3937D01*
G01X1226378D02*
G03Y1374803I0J-3937D01*
G01X1195669D02*
G03Y1382677I0J3937D01*
G01X1226378D02*
G03Y1374803I0J-3937D01*
G01X1216535Y1464567D02*
G03X1228346Y1476378I0J11811D01*
G01X1216535Y1464567D02*
G03X1228346Y1476378I0J11811D01*
G01Y1592126D02*
Y1476378D01*
G01Y1592126D02*
Y1476378D01*
G01X1220472Y1654331D02*
Y1476378D01*
G01X1216535Y1472441D02*
G03X1220472Y1476378I0J3937D01*
G01X1216535Y1472441D02*
G03X1220472Y1476378I0J3937D01*
G01D02*
Y1654331D01*
G01X1191870Y1574693D02*
G03X1198795Y1561563I37662J11472D01*
G01X1191870Y1574693D02*
G03X1198795Y1561562I37662J11471D01*
G01X1228346Y1592126D02*
G03X1220472I-3937J0D01*
G01X1228346D02*
G03X1220472I-3937J0D01*
G01X1232283Y1658268D02*
X1442382D01*
G01X1232283D02*
G03X1228346Y1654331I0J-3937D01*
G01X1232283Y1658268D02*
X1442382D01*
G01X1232283D02*
G03X1228346Y1654331I0J-3937D01*
G01D02*
Y1622835D01*
G01Y1654331D02*
Y1622835D01*
G01X1220472Y1654331D02*
G03X1216535Y1658268I-3937J0D01*
G01X1220472Y1654331D02*
G03X1216535Y1658268I-3937J0D01*
G01X1220472Y1622835D02*
G03X1228346I3937J0D01*
G01X1220472D02*
G03X1228346I3937J0D01*
G01X1284965Y378885D02*
G03X1318776I16906J-13531D01*
G01X1284965D02*
G03X1318775I16905J-13531D01*
G01X1284965Y831641D02*
G03X1318776I16906J-13531D01*
G01X1284965D02*
G03X1318775I16905J-13531D01*
G01X1284965Y1284397D02*
G03X1318776I16906J-13531D01*
G01X1284965D02*
G03X1318775I16905J-13531D01*
G01X1315748Y-7874D02*
G03Y0I0J3937D01*
G01Y-7874D02*
G03Y0I0J3937D01*
G01X1311850Y392016D02*
G03X1291890I-9980J-3040D01*
G01X1311850D02*
G03X1318776Y378885I37662J11473D01*
G01X1311851Y392016D02*
G03X1291890I-9980J-3039D01*
G01X1311851D02*
G03X1318775Y378885I37663J11469D01*
G01X1284965D02*
G03X1291890Y392016I-30737J24602D01*
G01X1284965Y378885D02*
G03X1291890Y392016I-30737J24602D01*
G01X1284965Y831641D02*
G03X1291890Y844772I-30737J24602D01*
G01X1311850D02*
G03X1318776Y831641I37662J11473D01*
G01X1284965D02*
G03X1291890Y844772I-30737J24602D01*
G01X1311851D02*
G03X1318775Y831641I37663J11469D01*
G01X1311850Y844772D02*
G03X1291890I-9980J-3040D01*
G01X1311851D02*
G03X1291890I-9980J-3039D01*
G01X1284965Y1284397D02*
G03X1291890Y1297528I-30737J24602D01*
G01X1311850D02*
G03X1291890I-9980J-3040D01*
G01X1311850D02*
G03X1318776Y1284397I37661J11473D01*
G01X1284965D02*
G03X1291890Y1297528I-30737J24602D01*
G01X1311851D02*
G03X1291890I-9980J-3040D01*
G01X1311851D02*
G03X1318775Y1284397I37663J11469D01*
G01X1377953Y3937D02*
Y51181D01*
G01Y3937D02*
Y51181D01*
G01X1370079Y3937D02*
Y55118D01*
G01X1366142Y0D02*
G03X1370079Y3937I0J3937D01*
G01X1366142Y-7874D02*
G03X1377953Y3937I0J11811D01*
G01X1346457Y-7874D02*
X1366142D01*
G01Y0D02*
G03X1370079Y3937I0J3937D01*
G01D02*
Y55118D01*
G01X1346457Y-7874D02*
X1366142D01*
G01D02*
G03X1377953Y3937I0J11811D01*
G01X1346457Y0D02*
G03Y-7874I0J-3937D01*
G01Y0D02*
G03Y-7874I0J-3937D01*
G01X1374016Y59055D02*
G03X1370079Y55118I0J-3937D01*
G01X1374016Y59056D02*
G03X1370079Y55118I0J-3937D01*
G01X1374016Y59055D02*
X1555118D01*
G01X1377953Y51181D02*
X1551181D01*
G01X1374016Y59055D02*
X1555118D01*
G01X1377953Y51181D02*
X1551181D01*
G01X1442382Y1658268D02*
G03X1450256I3937J0D01*
G01X1442382D02*
G03X1450256I3937J0D01*
G01D02*
X1919843D01*
G01X1450256D02*
X1919843D01*
G01X1562992Y0D02*
X1930906D01*
G01X1559055Y55118D02*
Y3937D01*
G01D02*
G03X1562992Y0I3937J0D01*
G01Y-7874D02*
X1593701D01*
G01X1559055Y55118D02*
Y3937D01*
G01D02*
G03X1562992Y0I3937J0D01*
G01D02*
X1930906D01*
G01X1562992Y-7874D02*
X1593701D01*
G01X1551181Y51181D02*
Y3937D01*
G01D02*
G03X1562992Y-7874I11811J0D01*
G01X1551181Y51181D02*
Y3937D01*
G01D02*
G03X1562992Y-7874I11811J0D01*
G01X1559055Y55118D02*
G03X1555118Y59055I-3937J0D01*
G01X1559055Y55118D02*
G03X1555118Y59055I-3937J0D01*
G01X1532996Y378885D02*
G03X1566807I16906J-13531D01*
G01X1532996D02*
G03X1566807I16906J-13531D01*
G01X1559882Y392016D02*
G03X1566807Y378885I37662J11471D01*
G01X1559882Y392016D02*
G03X1566807Y378885I37662J11471D01*
G01X1559882Y392016D02*
G03X1539921I-9980J-3039D01*
G01X1559882D02*
G03X1539921I-9980J-3039D01*
G01X1532996Y378885D02*
G03X1539921Y392016I-30737J24602D01*
G01X1532996Y378885D02*
G03X1539921Y392016I-30737J24602D01*
G01X1559882Y844772D02*
G03X1566807Y831641I37662J11471D01*
G01X1559882Y844772D02*
G03X1566807Y831641I37662J11471D01*
G01X1532996D02*
G03X1539921Y844772I-30737J24602D01*
G01X1532996Y831641D02*
G03X1539921Y844772I-30737J24602D01*
G01X1532996Y831641D02*
G03X1566807I16906J-13531D01*
G01X1532996D02*
G03X1566807I16906J-13531D01*
G01X1559882Y844772D02*
G03X1539921I-9980J-3040D01*
G01X1559882D02*
G03X1539921I-9980J-3039D01*
G01X1532996Y1284397D02*
G03X1566807I16906J-13531D01*
G01X1532996D02*
G03X1566807I16906J-13531D01*
G01X1559882Y1297528D02*
G03X1566807Y1284397I37662J11471D01*
G01X1559882Y1297528D02*
G03X1566807Y1284397I37662J11471D01*
G01X1559882Y1297528D02*
G03X1539921I-9980J-3040D01*
G01X1532996Y1284397D02*
G03X1539921Y1297528I-30737J24602D01*
G01X1532996Y1284397D02*
G03X1539921Y1297528I-30737J24602D01*
G01X1559882D02*
G03X1539921I-9980J-3040D01*
G01X1563976Y1382677D02*
G03Y1374803I0J-3937D01*
G01Y1382677D02*
G03Y1374803I0J-3937D01*
G01X1524606D02*
G03Y1382677I0J3937D01*
G01Y1374803D02*
G03Y1382677I0J3937D01*
G01X1864567D02*
X1563976D01*
G01X1864567D02*
X1563976D01*
G01X1593701Y-7874D02*
G03Y0I0J3937D01*
G01Y-7874D02*
G03Y0I0J3937D01*
G01X1633071D02*
G03Y-7874I0J-3937D01*
G01D02*
X1880512D01*
G01X1633071D02*
X1880512D01*
G01X1633071Y0D02*
G03Y-7874I0J-3937D01*
G01X1693996Y829921D02*
G03X1653839I-20078J0D01*
G01X1693996D02*
G03I-20079J0D01*
G01X1653839D02*
G03X1693996I20078J0D01*
G01X1781028Y378885D02*
G03X1814839I16906J-13531D01*
G01X1781028D02*
G03X1814838I16905J-13531D01*
G01X1807913Y392016D02*
G03X1814839Y378885I37662J11473D01*
G01X1807914Y392016D02*
G03X1814838Y378885I37663J11469D01*
G01X1807913Y392016D02*
G03X1787953I-9980J-3040D01*
G01X1807914D02*
G03X1787953I-9980J-3039D01*
G01X1781028Y378885D02*
G03X1787953Y392016I-30737J24602D01*
G01X1781028Y378885D02*
G03X1787953Y392016I-30737J24602D01*
G01X1807913Y844772D02*
G03X1814839Y831641I37662J11473D01*
G01X1807914Y844772D02*
G03X1814838Y831641I37663J11469D01*
G01X1781028D02*
G03X1787953Y844772I-30737J24602D01*
G01X1781028Y831641D02*
G03X1787953Y844772I-30737J24602D01*
G01X1781028Y831641D02*
G03X1814839I16906J-13531D01*
G01X1781028D02*
G03X1814838I16905J-13531D01*
G01X1807913Y844772D02*
G03X1787953I-9980J-3040D01*
G01X1807914D02*
G03X1787953I-9980J-3039D01*
G01X1781028Y1284397D02*
G03X1814839I16906J-13531D01*
G01X1781028D02*
G03X1814838I16905J-13531D01*
G01X1807913Y1297528D02*
G03X1814839Y1284397I37661J11473D01*
G01X1807914Y1297528D02*
G03X1814838Y1284397I37663J11469D01*
G01X1807913Y1297528D02*
G03X1787953I-9980J-3040D01*
G01X1781028Y1284397D02*
G03X1787953Y1297528I-30737J24602D01*
G01X1781028Y1284397D02*
G03X1787953Y1297528I-30737J24602D01*
G01X1807914D02*
G03X1787953I-9980J-3040D01*
G01X1911220Y0D02*
G03Y-7874I0J-3937D01*
G01Y0D02*
G03Y-7874I0J-3937D01*
G01X1880512D02*
G03Y0I0J3937D01*
G01Y-7874D02*
G03Y0I0J3937D01*
G01X1930906Y1382677D02*
X1895276D01*
G01D02*
G03Y1374803I0J-3937D01*
G01X1930906Y1382677D02*
X1895276D01*
G01D02*
G03Y1374803I0J-3937D01*
G01X1864567D02*
G03Y1382677I0J3937D01*
G01Y1374803D02*
G03Y1382677I0J3937D01*
G01X1919843Y-152756D02*
G03X1934843Y-137756I0J15000D01*
G01X1919843Y-152756D02*
G03X1934843Y-137756I0J15000D01*
G01Y-11811D02*
Y-137756D01*
G01Y-11811D02*
Y-137756D01*
G01X1930906Y0D02*
G03X1934843Y3937I0J3937D01*
G01X1930906Y0D02*
G03X1934843Y3937I0J3937D01*
G01Y-11811D02*
G03X1930906Y-7874I-3937J0D01*
G01X1934843Y-11811D02*
G03X1930906Y-7874I-3937J0D01*
G01X1911220D02*
X1930906D01*
G01X1911220D02*
X1930906D01*
G01X1934843Y1370866D02*
Y3937D01*
G01D02*
Y1370866D01*
G01D02*
G03X1930906Y1374803I-3937J0D01*
G01X1934843Y1370866D02*
G03X1930906Y1374803I-3937J0D01*
G01Y1382677D02*
G03X1934843Y1386614I0J3937D01*
G01X1930906Y1382677D02*
G03X1934843Y1386614I0J3937D01*
G01D02*
Y1643268D01*
G01Y1386614D02*
Y1643268D01*
G01D02*
G03X1919843Y1658268I-15000J0D01*
G01X1934843Y1643268D02*
G03X1919843Y1658268I-15000J0D01*
G54D12*
G01X302500Y372200D02*
X314200Y360500D01*
G01X302500Y475712D02*
Y372200D01*
G01X310085Y369683D02*
X316534Y363234D01*
G01X310085Y482325D02*
Y369683D01*
G01X292153Y486059D02*
X302500Y475712D01*
G01X306388Y486022D02*
X310085Y482325D01*
G01X317740Y360500D02*
X320474Y363234D01*
G01X314200Y360500D02*
X317740D01*
G01X315925Y380083D02*
X316534Y379474D01*
G01X315925Y485385D02*
Y380083D01*
G01X320925Y379925D02*
X320474Y379474D01*
G01X320925Y485385D02*
Y379925D01*
G01X320474Y937689D02*
Y832229D01*
G01X317800Y833495D02*
Y931400D01*
G01X316534Y832229D02*
X317800Y833495D01*
G01X320925Y938140D02*
X320474Y937689D01*
G01X317800Y931400D02*
X315600Y933600D01*
G01X440747Y806010D02*
X398254Y763517D01*
G01X407714Y770272D02*
Y761291D01*
G01X444687Y807245D02*
X407714Y770272D01*
G01X440138Y380083D02*
X440747Y379474D01*
G01X440138Y487743D02*
Y380083D01*
G01X445138Y379925D02*
X444687Y379474D01*
G01X445138Y487743D02*
Y379925D01*
G01X441853Y360400D02*
X444687Y363234D01*
G01X438513Y360400D02*
X441853D01*
G01X426713Y372200D02*
X438513Y360400D01*
G01X426713Y475612D02*
Y372200D01*
G01X434298Y369683D02*
X440747Y363234D01*
G01X434298Y482225D02*
Y369683D01*
G01X416303Y486022D02*
X426713Y475612D01*
G01X430538Y485985D02*
X434298Y482225D01*
G01X440747Y816765D02*
Y806010D01*
G01X444687Y816765D02*
Y807245D01*
G01X440747Y937531D02*
Y832229D01*
G01X447600Y835142D02*
X444687Y832229D01*
G01X447600Y935678D02*
Y835142D01*
G01X440138Y938140D02*
X440747Y937531D01*
G01X445138Y938140D02*
X447600Y935678D01*
G01X550474Y372651D02*
X562725Y360400D01*
G01X550474Y408926D02*
Y372651D01*
G01X539350Y441217D02*
X568899Y411668D01*
G01X539350Y487659D02*
Y441217D01*
G01X534350D02*
X563899Y411668D01*
G01X534350Y487659D02*
Y441217D01*
G01X510621Y448779D02*
X550474Y408926D01*
G01X510621Y486059D02*
Y448779D01*
G01X524856Y440906D02*
X558059Y407703D01*
G01X524856Y486022D02*
Y440906D01*
G01X568899Y411668D02*
Y379474D01*
G01X563899Y380534D02*
X564959Y379474D01*
G01X563899Y411668D02*
Y380534D01*
G01X566065Y360400D02*
X568899Y363234D01*
G01X562725Y360400D02*
X566065D01*
G01X558059Y370134D02*
X564959Y363234D01*
G01X558059Y407703D02*
Y370134D01*
G01X564959Y941031D02*
Y832229D01*
G01X568899Y941189D02*
Y832229D01*
G01X564350Y941640D02*
X564959Y941031D01*
G01X569350Y941640D02*
X568899Y941189D01*
G01X624028Y477283D02*
X677849Y423462D01*
G01X647663Y477786D02*
X688112Y437337D01*
G01X647663Y502400D02*
Y477786D01*
G01X638263Y475284D02*
X681272Y432275D01*
G01X638263Y503494D02*
Y475284D01*
G01X624028Y503558D02*
Y477283D01*
G01X652663Y477786D02*
X693112Y437337D01*
G01X652663Y502400D02*
Y477786D01*
G01X687649Y355251D02*
X689232D01*
G01X677849Y365051D02*
X687649Y355251D01*
G01X688112Y387036D02*
X689172Y385976D01*
G01X688112Y437337D02*
Y387036D01*
G01X681272Y366878D02*
X689172Y358978D01*
G01X681272Y432275D02*
Y366878D01*
G01X677849Y423462D02*
Y365051D01*
G01X693112Y437337D02*
Y385976D01*
G01X792497Y1185845D02*
Y1319537D01*
G01X802036Y1176306D02*
X792497Y1185845D01*
G01Y1319537D02*
X792336D01*
G01X822175Y16098D02*
X924171D01*
G01X802350Y35923D02*
X822175Y16098D01*
G01X816995Y14175D02*
X802362Y-458D01*
G01X923028Y14175D02*
X816995D01*
G01X840246Y6829D02*
X833671Y254D01*
G01X920133Y6829D02*
X840246D01*
G01X823003Y12309D02*
X810236Y-458D01*
G01X922302Y12309D02*
X823003D01*
G01X829012Y10444D02*
X818110Y-458D01*
G01X921788Y10444D02*
X829012D01*
G01X835137Y8695D02*
X825984Y-458D01*
G01X920739Y8695D02*
X835137D01*
G01X802036Y1164244D02*
Y1176306D01*
G01X883409Y1459291D02*
X905512Y1437188D01*
G01X883409Y1497797D02*
Y1459291D01*
G01X886760Y1463178D02*
X908862Y1441076D01*
G01X886760Y1496410D02*
Y1463178D01*
G01X885084Y1462485D02*
X907187Y1440382D01*
G01X885084Y1497103D02*
Y1462485D01*
G01X880059Y1457903D02*
X902162Y1435800D01*
G01X880059Y1499185D02*
Y1457903D01*
G01X876709Y1456515D02*
X898812Y1434412D01*
G01X876709Y1484846D02*
Y1456515D01*
G01X878384Y1457209D02*
X900487Y1435106D01*
G01X878384Y1485540D02*
Y1457209D01*
G01X881734Y1458597D02*
X903837Y1436494D01*
G01X881734Y1498491D02*
Y1458597D01*
G01X883550Y1497938D02*
X883409Y1497797D01*
G01X883550Y1504958D02*
Y1497938D01*
G01X881901Y1506607D02*
X883550Y1504958D01*
G01X881901Y1568801D02*
Y1506607D01*
G01X892800Y1493660D02*
X897349Y1489111D01*
G01X888960Y1493660D02*
X892800D01*
G01X888800Y1493500D02*
X888960Y1493660D01*
G01X887505Y1497155D02*
X886760Y1496410D01*
G01X887505Y1507346D02*
Y1497155D01*
G01X885662Y1509189D02*
X887505Y1507346D01*
G01X885662Y1559172D02*
Y1509189D01*
G01X885225Y1497244D02*
X885084Y1497103D01*
G01X885225Y1505965D02*
Y1497244D01*
G01X883576Y1507614D02*
X885225Y1505965D01*
G01X883576Y1568107D02*
Y1507614D01*
G01X880200Y1499326D02*
X880059Y1499185D01*
G01X880200Y1503570D02*
Y1499326D01*
G01X878551Y1505219D02*
X880200Y1503570D01*
G01X878551Y1570189D02*
Y1505219D01*
G01X872275Y1489280D02*
X876709Y1484846D01*
G01X872275Y1568744D02*
Y1489280D01*
G01X873950Y1489974D02*
X878384Y1485540D01*
G01X873950Y1568050D02*
Y1489974D01*
G01X881875Y1498632D02*
X881734Y1498491D01*
G01X881875Y1504264D02*
Y1498632D01*
G01X880226Y1505913D02*
X881875Y1504264D01*
G01X880226Y1569495D02*
Y1505913D01*
G01X893020Y1566530D02*
X885662Y1559172D01*
G01X900243Y1587143D02*
X881901Y1568801D01*
G01X899230Y1583761D02*
X883576Y1568107D01*
G01X879230Y1570868D02*
X878551Y1570189D01*
G01X879230Y1570870D02*
Y1570868D01*
G01X879231Y1570870D02*
X879230D01*
G01X881230Y1572869D02*
X879231Y1570870D01*
G01X881231Y1572869D02*
X881230D01*
G01X890973Y1582611D02*
X881231Y1572869D01*
G01X890973Y1592125D02*
Y1582611D01*
G01X893042Y1594194D02*
X890973Y1592125D01*
G01X893042Y1617845D02*
Y1594194D01*
G01X884100Y1580569D02*
X872275Y1568744D01*
G01X884100Y1647631D02*
Y1580569D01*
G01X886730Y1580830D02*
X873950Y1568050D01*
G01X886730Y1626887D02*
Y1580830D01*
G01X880905Y1570174D02*
X880226Y1569495D01*
G01X880905Y1570175D02*
Y1570174D01*
G01X880906Y1570175D02*
X880905D01*
G01X894967Y1584236D02*
X880906Y1570175D01*
G01X897638Y1622441D02*
X893042Y1617845D01*
G01X889564Y1653095D02*
X884100Y1647631D01*
G01X893253Y1653095D02*
X889564D01*
G01X894359Y1651989D02*
X893253Y1653095D01*
G01X894359Y1649736D02*
Y1651989D01*
G01X897638Y1646457D02*
X894359Y1649736D01*
G01X890552Y1630709D02*
X886730Y1626887D01*
G01X938168Y2101D02*
X1111554D01*
G01X924171Y16098D02*
X938168Y2101D01*
G01X936882Y321D02*
X923028Y14175D01*
G01X1108316Y321D02*
X936882D01*
G01X933659Y-6697D02*
X920133Y6829D01*
G01X1095485Y-6697D02*
X933659D01*
G01X935969Y-1358D02*
X922302Y12309D01*
G01X1104679Y-1358D02*
X935969D01*
G01X935269Y-3037D02*
X921788Y10444D01*
G01X1101565Y-3037D02*
X935269D01*
G01X934266Y-4832D02*
X920739Y8695D01*
G01X1096403Y-4832D02*
X934266D01*
G01X942000Y737945D02*
X959385Y720560D01*
G01X942000Y752850D02*
Y737945D01*
G01X942813Y1164767D02*
X994948Y1112632D01*
G01X939400Y1163442D02*
X991598Y1111244D01*
G01X939400Y1272400D02*
Y1163442D01*
G01X941138Y1164073D02*
X993273Y1111938D01*
G01X941138Y1276662D02*
Y1164073D01*
G01X898812Y1312988D02*
X939400Y1272400D01*
G01X905512Y1324481D02*
X947738Y1282255D01*
G01X905512Y1437188D02*
Y1324481D01*
G01X910537Y1326564D02*
X952763Y1284338D01*
G01X908862Y1325870D02*
X951088Y1283644D01*
G01X907187Y1325175D02*
X949413Y1282949D01*
G01X902162Y1320138D02*
X942813Y1279487D01*
G01X902162Y1435800D02*
Y1320138D01*
G01X898812Y1434412D02*
Y1312988D01*
G01X900487Y1317313D02*
X941138Y1276662D01*
G01X900487Y1435106D02*
Y1317313D01*
G01X903837Y1321963D02*
X944488Y1281312D01*
G01X903837Y1436494D02*
Y1321963D01*
G01X910537Y1441770D02*
Y1326564D01*
G01X908862Y1441076D02*
Y1325870D01*
G01X907187Y1440382D02*
Y1325175D01*
G01X897349Y1454958D02*
X910537Y1441770D01*
G01X897349Y1489111D02*
Y1454958D01*
G01X900243Y1624167D02*
Y1587143D01*
G01X899584Y1583761D02*
X899230D01*
G01X902168Y1586345D02*
X899584Y1583761D01*
G01X902168Y1627754D02*
Y1586345D01*
G01X907800Y1584400D02*
X897400Y1574000D01*
G01X907800Y1633146D02*
Y1584400D01*
G01X894967Y1609928D02*
Y1584236D01*
G01X897638Y1612599D02*
X894967Y1609928D01*
G01X897638Y1626772D02*
X900243Y1624167D01*
G01X897638Y1632284D02*
X902168Y1627754D01*
G01X904725Y1636221D02*
X907800Y1633146D01*
G01X959385Y610014D02*
X998250Y571149D01*
G01X959385Y720560D02*
Y610014D01*
G01X947738Y1164580D02*
X998298Y1114020D01*
G01X952763Y1166662D02*
X1003323Y1116102D01*
G01X951088Y1165968D02*
X1001648Y1115408D01*
G01X949413Y1165274D02*
X999973Y1114714D01*
G01X944488Y1165461D02*
X996623Y1113326D01*
G01X947738Y1282255D02*
Y1164580D01*
G01X952763Y1284338D02*
Y1166662D01*
G01X951088Y1283644D02*
Y1165968D01*
G01X949413Y1282949D02*
Y1165274D01*
G01X942813Y1279487D02*
Y1164767D01*
G01X944488Y1281312D02*
Y1165461D01*
G01X1037961Y439729D02*
X1040180Y437510D01*
G01X1037961Y454063D02*
Y439729D01*
G01X998250Y493774D02*
X1037961Y454063D01*
G01X998250Y571149D02*
Y493774D01*
G01X1012974Y1024300D02*
Y1021240D01*
G01X1005730Y1031544D02*
X1012974Y1024300D01*
G01X1005730Y1046431D02*
Y1031544D01*
G01X1020654Y1038737D02*
Y1023940D01*
G01X1018094Y1027963D02*
Y1021240D01*
G01X1015000Y1031057D02*
X1018094Y1027963D01*
G01X1015000Y1042022D02*
Y1031057D01*
G01X1015534Y1026100D02*
Y1023840D01*
G01X1010018Y1031616D02*
X1015534Y1026100D01*
G01X1010018Y1044635D02*
Y1031616D01*
G01X1008943Y1007640D02*
X1013700D01*
G01X1002211Y1014372D02*
X1008943Y1007640D01*
G01X1002211Y1044288D02*
Y1014372D01*
G01X1019440Y1007140D02*
X1023214D01*
G01X1016302Y1004002D02*
X1019440Y1007140D01*
G01X1007843Y1004002D02*
X1016302D01*
G01X998861Y1012984D02*
X1007843Y1004002D01*
G01X998861Y1042900D02*
Y1012984D01*
G01X1022401Y1009103D02*
X1028657D01*
G01X1022387Y1009089D02*
X1022401Y1009103D01*
G01X1019020Y1009089D02*
X1022387D01*
G01X1015608Y1005677D02*
X1019020Y1009089D01*
G01X1008537Y1005677D02*
X1015608D01*
G01X1000536Y1013678D02*
X1008537Y1005677D01*
G01X1000536Y1043594D02*
Y1013678D01*
G01X1009509Y1013100D02*
Y1009850D01*
G01X1003886Y1018723D02*
X1009509Y1013100D01*
G01X1003886Y1045800D02*
Y1018723D01*
G01X998761Y1053400D02*
X1005730Y1046431D01*
G01X998761Y1053523D02*
Y1053400D01*
G01X998298Y1053986D02*
X998761Y1053523D01*
G01X998298Y1114020D02*
Y1053986D01*
G01X1003323Y1056068D02*
X1020654Y1038737D01*
G01X1003323Y1116102D02*
Y1056068D01*
G01X1001648Y1055374D02*
X1015000Y1042022D01*
G01X1001648Y1115408D02*
Y1055374D01*
G01X999973Y1054680D02*
X1010018Y1044635D01*
G01X999973Y1114714D02*
Y1054680D01*
G01X995411Y1051088D02*
X1002211Y1044288D01*
G01X995411Y1052135D02*
Y1051088D01*
G01X994948Y1052598D02*
X995411Y1052135D01*
G01X994948Y1112632D02*
Y1052598D01*
G01X994023Y1047738D02*
X998861Y1042900D01*
G01X994022Y1047738D02*
X994023D01*
G01X992061Y1049699D02*
X994022Y1047738D01*
G01X992061Y1049700D02*
Y1049699D01*
G01X991800Y1049961D02*
X992061Y1049700D01*
G01X991800Y1051008D02*
Y1049961D01*
G01X991598Y1051210D02*
X991800Y1051008D01*
G01X991598Y1111244D02*
Y1051210D01*
G01X994717Y1049413D02*
X1000536Y1043594D01*
G01X994716Y1049413D02*
X994717D01*
G01X993736Y1050393D02*
X994716Y1049413D01*
G01X993736Y1051441D02*
Y1050393D01*
G01X993273Y1051904D02*
X993736Y1051441D01*
G01X993273Y1111938D02*
Y1051904D01*
G01X997086Y1052600D02*
X1003886Y1045800D01*
G01X997086Y1052829D02*
Y1052600D01*
G01X996623Y1053292D02*
X997086Y1052829D01*
G01X996623Y1113326D02*
Y1053292D01*
G01X1074900Y1253300D02*
X1051300D01*
G01X1092800Y1235400D02*
X1074900Y1253300D01*
G01X1073513Y1258687D02*
X1047000D01*
G01X1090850Y1241350D02*
X1073513Y1258687D01*
G01X1123085Y-34297D02*
X1095485Y-6697D01*
G01X1128765Y-34297D02*
X1123085D01*
G01X1138474Y-35153D02*
X1104679Y-1358D01*
G01X1136050Y-37522D02*
X1101565Y-3037D01*
G01X1142293Y-37522D02*
X1136050D01*
G01X1122411Y-30840D02*
X1096403Y-4832D01*
G01X1124024Y-30840D02*
X1122411D01*
G01X1111554Y2101D02*
X1144793Y-31138D01*
G01X1139808Y-31171D02*
X1108316Y321D01*
G01X1112600Y1220600D02*
X1143310D01*
G01X1109593Y1217593D02*
X1112600Y1220600D01*
G01X1109593Y1216949D02*
Y1217593D01*
G01X1116444Y1226950D02*
X1142639D01*
G01X1113530Y1224036D02*
X1116444Y1226950D01*
G01X1105316Y1235400D02*
X1092800D01*
G01X1109593Y1231123D02*
X1105316Y1235400D01*
G01X1110389Y1241350D02*
X1090850D01*
G01X1113530Y1238209D02*
X1110389Y1241350D01*
G01X1146668Y-31138D02*
X1146768Y-31238D01*
G01X1144793Y-31138D02*
X1146668D01*
G01X1149699Y-35153D02*
X1138474D01*
G01X1147697Y1216213D02*
X1152700D01*
G01X1143310Y1220600D02*
X1147697Y1216213D01*
G01X1146527Y1223062D02*
X1152800D01*
G01X1142639Y1226950D02*
X1146527Y1223062D01*
M02*
